G04 ================== begin FILE IDENTIFICATION RECORD ==================*
G04 Layout Name:  12432-1.brd*
G04 Film Name:    DIF_REF_TOP*
G04 File Format:  Gerber RS274X*
G04 File Origin:  Cadence Allegro 16.2-S037*
G04 Origin Date:  Wed Oct 17 11:00:22 2012*
G04 *
G04 Layer:  BOARD GEOMETRY/OUTLINE*
G04 Layer:  BOARD GEOMETRY/DIF_REF_TOP*
G04 Layer:  BOARD GEOMETRY/PANEL_OUTLINE*
G04 *
G04 Offset:    (0.00 0.00)*
G04 Mirror:    No*
G04 Mode:      Positive*
G04 Rotation:  0*
G04 FullContactRelief:  No*
G04 UndefLineWidth:     6.00*
G04 ================== end FILE IDENTIFICATION RECORD ====================*
%FSLAX35Y35*MOIN*%
%IR0*IPPOS*OFA0.00000B0.00000*MIA0B0*SFA1.00000B1.00000*%
%ADD10C,.01*%
%ADD11C,.004*%
%ADD12C,.006*%
G75*
%LPD*%
G75*
G54D10*
G01X-78740Y15000D02*
G03X-63740Y0I15000J0D01*
G01X-78740Y15000D02*
Y319646D01*
G01X-63740Y334646D02*
G03X-78740Y319646I0J-15000D01*
G01Y908315D02*
G03X-63740Y893315I15000J0D01*
G01X-78740Y908315D02*
Y1304286D01*
G01X-63740Y1319286D02*
G03X-78740Y1304286I0J-15000D01*
G01Y1892953D02*
G03X-63740Y1877953I15000J0D01*
G01X-78740Y1892953D02*
Y1977126D01*
G01X-63740Y1992126D02*
G03X-78740Y1977126I0J-15000D01*
G01X-7874Y0D02*
X-63740D01*
G01X-7874Y334646D02*
X-63740D01*
G01X-7874Y893315D02*
X-63740D01*
G01X-7874Y1319286D02*
X-63740D01*
G01X-7874Y1877953D02*
X-63740D01*
G01X-7874Y1992126D02*
X-63740D01*
G01X-7874Y17253D02*
Y0D01*
G01X0Y17214D02*
G03X-7874I-3937J0D01*
G01Y41772D02*
Y167110D01*
G01Y41772D02*
G03X0I3937J0D01*
G01Y167110D02*
G03X-7874I-3937J0D01*
G01Y191667D02*
Y308383D01*
G01Y191667D02*
G03X0I3937J0D01*
G01Y308383D02*
G03X-7874I-3937J0D01*
G01Y331986D02*
Y334646D01*
G01Y332003D02*
G03X0I3937J0D01*
G01X-7874Y905988D02*
Y893315D01*
G01X0Y905988D02*
G03X-7874I-3937J0D01*
G01Y1106301D02*
Y933234D01*
G01D02*
G03X0I3937J0D01*
G01Y1106301D02*
G03X-7874I-3937J0D01*
G01Y1280567D02*
Y1129921D01*
G01D02*
G03X0I3937J0D01*
G01Y1280567D02*
G03X-7874I-3937J0D01*
G01Y1309889D02*
Y1319286D01*
G01Y1309889D02*
G03X0I3937J0D01*
G01X-7874Y1889223D02*
Y1877953D01*
G01X0Y1889223D02*
G03X-7874I-3937J0D01*
G01X0D02*
G03X-7874I-3937J0D01*
G01Y1912843D02*
Y1962927D01*
G01Y1912843D02*
G03X0I3937J0D01*
G01Y1962927D02*
G03X-7874I-3937J0D01*
G01X0D02*
G03X-7874I-3937J0D01*
G01Y1986547D02*
Y1992126D01*
G01Y1986547D02*
G03X0I3937J0D01*
G01X3937Y0D02*
X1029528D01*
G01X0Y3937D02*
G03X3937Y0I3937J0D01*
G01X0Y409646D02*
Y3937D01*
G01X3937Y413583D02*
X0Y409646D01*
G01X19882Y413583D02*
X3937D01*
G01Y421063D02*
X19882D01*
G01X0Y425000D02*
X3937Y421063D01*
G01X0Y819094D02*
Y425000D01*
G01X3937Y823031D02*
X0Y819094D01*
G01X19882Y823031D02*
X3937D01*
G01Y830512D02*
X19882D01*
G01X0Y834449D02*
X3937Y830512D01*
G01X0Y1393898D02*
Y834449D01*
G01X3937Y1397835D02*
X0Y1393898D01*
G01X19882Y1397835D02*
X3937D01*
G01Y1405315D02*
X19882D01*
G01X0Y1409252D02*
X3937Y1405315D01*
G01X0Y1803346D02*
Y1409252D01*
G01X3937Y1807283D02*
X0Y1803346D01*
G01X19882Y1807283D02*
X3937D01*
G01Y1814764D02*
X19882D01*
G01X0Y1818701D02*
X3937Y1814764D01*
G01X0Y1988189D02*
Y1818701D01*
G01X3937Y1992126D02*
G03X0Y1988189I0J-3937D01*
G01X1029528Y1992126D02*
X3937D01*
G01X19882Y413583D02*
G03Y421063I0J3740D01*
G01Y823031D02*
G03Y830512I0J3741D01*
G01Y1397835D02*
G03Y1405315I0J3740D01*
G01Y1807283D02*
G03Y1814764I0J3740D01*
G01X989744Y1616083D02*
X1015354D01*
G01X989744D02*
G03Y1611870I0J-2107D01*
G01X1015354D02*
X989744D01*
G01X1033465Y3937D02*
Y1424882D01*
G01X1029528Y0D02*
G03X1033465Y3937I0J3937D01*
G01X1041338Y24677D02*
G03X1033464I-3937J0D01*
G01X1041338D02*
G03X1033464I-3937J0D01*
G01Y48297D02*
G03X1041338I3937J0D01*
G01Y217343D02*
G03X1033464I-3937J0D01*
G01X1041338D02*
G03X1033464I-3937J0D01*
G01Y240964D02*
G03X1041338I3937J0D01*
G01X1033464D02*
G03X1041338I3937J0D01*
G01Y445039D02*
G03X1033464I-3937J0D01*
G01X1041338D02*
G03X1033464I-3937J0D01*
G01Y468659D02*
G03X1041338I3937J0D01*
G01X1033464D02*
G03X1041338I3937J0D01*
G01Y697473D02*
G03X1033464I-3937J0D01*
G01X1041338D02*
G03X1033464I-3937J0D01*
G01Y721093D02*
G03X1041338I3937J0D01*
G01X1033464D02*
G03X1041338I3937J0D01*
G01Y996852D02*
G03X1033464I-3937J0D01*
G01X1041338D02*
G03X1033464I-3937J0D01*
G01Y1020472D02*
G03X1041338I3937J0D01*
G01X1033464D02*
G03X1041338I3937J0D01*
G01Y1344060D02*
G03X1033464I-3937J0D01*
G01X1041338D02*
G03X1033464I-3937J0D01*
G01Y1367680D02*
G03X1041338I3937J0D01*
G01X1033464D02*
G03X1041338I3937J0D01*
G01X1033465Y1424882D02*
X1029528Y1428819D01*
G01X1019291Y1433740D02*
Y1607933D01*
G01Y1433740D02*
G03X1024213Y1428819I4921J0D01*
G01X1029528D02*
X1024213D01*
G01X1015354Y1616083D02*
X1019291Y1620020D01*
G01Y1607933D02*
X1015354Y1611870D01*
G01X1019291Y1620020D02*
Y1676496D01*
G01X1029528Y1681417D02*
X1033465Y1685354D01*
G01X1024213Y1681417D02*
G03X1019291Y1676496I-1J-4921D01*
G01X1033465Y1685354D02*
Y1988189D01*
G01X1024213Y1681417D02*
X1029528D01*
G01X1041338Y1739719D02*
G03X1033464I-3937J0D01*
G01X1041338D02*
G03X1033464I-3937J0D01*
G01Y1763339D02*
G03X1041338I3937J0D01*
G01X1033464D02*
G03X1041338I3937J0D01*
G01Y1959242D02*
G03X1033464I-3937J0D01*
G01X1041338D02*
G03X1033464I-3937J0D01*
G01X1033465Y1988189D02*
G03X1029528Y1992126I-3937J0D01*
G01X1033464Y1982862D02*
G03X1041338I3937J0D01*
G01Y24677D02*
Y0D01*
G01D02*
X1097205D01*
G01X1041338Y217343D02*
Y48297D01*
G01Y445039D02*
Y240964D01*
G01Y697473D02*
Y468601D01*
G01Y996852D02*
Y721093D01*
G01Y1344060D02*
Y1020472D01*
G01Y1367680D02*
Y1393701D01*
G01D02*
X1097205D01*
G01X1041338Y1733129D02*
Y1716536D01*
G01X1065043D02*
X1041338D01*
G01Y1739719D02*
Y1731536D01*
G01Y1959242D02*
Y1763310D01*
G01Y1992126D02*
X1097205D01*
G01X1041338Y1982862D02*
Y1992126D01*
G01X1056338Y1716536D02*
X1097205D01*
G01Y0D02*
G03X1112205Y15000I0J15000D01*
G01Y1378701D02*
G03X1097205Y1393701I-15000J0D01*
G01Y1716536D02*
G03X1112205Y1731536I0J15000D01*
G01Y1977126D02*
G03X1097205Y1992126I-15000J0D01*
G01X1112205Y648419D02*
Y15000D01*
G01Y656293D02*
G03Y648419I0J-3937D01*
G01Y1378701D02*
Y656293D01*
G01Y1977126D02*
Y1731536D01*
G54D11*
G01X12569Y387789D02*
X12575Y387795D01*
G01D02*
X18881D01*
G01X19044Y383858D02*
X12575D01*
G01D02*
X12569Y383852D01*
G01Y403537D02*
X18605D01*
G01D02*
X18611Y403543D01*
G01D02*
G02X20451Y402781I0J-2602D01*
G01X18958Y399606D02*
X12575D01*
G01D02*
X12569Y399600D01*
G01Y427161D02*
X17730D01*
G01D02*
X17736Y427167D01*
G01D02*
G02X21398Y425650I0J-5179D01*
G01X21036Y423229D02*
X12575D01*
G01D02*
X12569Y423223D01*
G01Y442909D02*
X19037D01*
G01X12569Y438972D02*
X19018D01*
G01X12569Y458657D02*
X18430D01*
G01D02*
X18436Y458663D01*
G01D02*
G02X20476Y457818I0J-2885D01*
G01X12569Y454720D02*
X18476D01*
G01D02*
X18482Y454726D01*
G01D02*
G03X20493Y455559I0J2844D01*
G01X12569Y474405D02*
X19482D01*
G01X12569Y470468D02*
X19413D01*
G01X12569Y490153D02*
X18956D01*
G01X12569Y486216D02*
X18747D01*
G01D02*
X18753Y486222D01*
G01D02*
G03X20711Y487033I0J2769D01*
G01X12569Y505901D02*
X18472D01*
G01D02*
X18478Y505907D01*
G01D02*
G02X20455Y505088I0J-2796D01*
G01X12569Y501964D02*
X18409D01*
G01D02*
X18415Y501970D01*
G01D02*
G03X20585Y502869I0J3069D01*
G01X12569Y521649D02*
X18908D01*
G01X12569Y517712D02*
X19254D01*
G01X12569Y537397D02*
X19135D01*
G01X20331Y533466D02*
X12575D01*
G01D02*
X12569Y533460D01*
G01Y572830D02*
X18469D01*
G01D02*
X18475Y572836D01*
G01D02*
G02X20527Y571986I0J-2902D01*
G01X12569Y568893D02*
X18476D01*
G01D02*
X18482Y568899D01*
G01D02*
G03X20877Y569891I0J3387D01*
G01X12569Y620074D02*
X18336D01*
G01D02*
X18342Y620080D01*
G01D02*
G03X20486Y620968I0J3032D01*
G01X12569Y639759D02*
X18303D01*
G01D02*
X18309Y639765D01*
G01D02*
G02X20446Y638880I0J-3022D01*
G01X12569Y635822D02*
X18370D01*
G01D02*
X18376Y635828D01*
G01D02*
G03X20445Y636685I0J2926D01*
G01X12569Y624011D02*
X18285D01*
G01D02*
X18291Y624017D01*
G01D02*
G02X20471Y623114I0J-3083D01*
G01X12569Y655507D02*
X18286D01*
G01D02*
X18292Y655513D01*
G01D02*
G02X20470Y654611I0J-3080D01*
G01X12569Y651570D02*
X18371D01*
G01D02*
X18377Y651576D01*
G01D02*
G03X20441Y652431I0J2919D01*
G01X12569Y671255D02*
X19494D01*
G01X12569Y667318D02*
X18669D01*
G01D02*
X18675Y667324D01*
G01D02*
G03X20196Y667954I0J2151D01*
G01X12569Y683066D02*
X18894D01*
G01X12569Y687003D02*
X19594D01*
G01X12569Y1372041D02*
X18441D01*
G01D02*
X18447Y1372047D01*
G01D02*
G02X20262Y1371295I0J-2567D01*
G01X12569Y1368104D02*
X19025D01*
G01X12569Y1383852D02*
X19028D01*
G01X12569Y1387789D02*
X18239D01*
G01D02*
X18245Y1387795D01*
G01D02*
G02X20522Y1386852I0J-3220D01*
G01X12569Y1411413D02*
X18457D01*
G01D02*
X18463Y1411419D01*
G01D02*
G02X20455Y1410594I0J-2817D01*
G01X12569Y1407475D02*
X12575Y1407481D01*
G01D02*
X19730D01*
G01X18209Y1427161D02*
X18215Y1427167D01*
G01X12569Y1423224D02*
X18211D01*
G01D02*
X18217Y1423230D01*
G01D02*
G03X20634Y1424231I0J3418D01*
G01X12569Y1427161D02*
X18209D01*
G01X18215Y1427167D02*
G02X20557Y1426197I0J-3312D01*
G01X12569Y1442909D02*
X18287D01*
G01D02*
X18293Y1442915D01*
G01D02*
G02X20471Y1442013I0J-3080D01*
G01X12569Y1438972D02*
X18298D01*
G01D02*
X18304Y1438978D01*
G01D02*
G03X20535Y1439902I0J3155D01*
G01X12569Y1458657D02*
X19265D01*
G01X12569Y1454720D02*
X19202D01*
G01X12569Y1490153D02*
X18712D01*
G01D02*
X18718Y1490159D01*
G01D02*
G02X20978Y1489223I0J-3196D01*
G01X12569Y1486216D02*
X18744D01*
G01D02*
X18750Y1486222D01*
G01D02*
G03X20865Y1487098I0J2991D01*
G01X12569Y1474405D02*
X19377D01*
G01X12569Y1470468D02*
X19241D01*
G01X12569Y1505901D02*
X18420D01*
G01D02*
X18426Y1505907D01*
G01D02*
G02X20724Y1504955I0J-3250D01*
G01X12569Y1501964D02*
X18468D01*
G01D02*
X18474Y1501970D01*
G01D02*
G03X20751Y1502913I0J3220D01*
G01X12569Y1521649D02*
X19210D01*
G01X12569Y1517712D02*
X19231D01*
G01X12569Y1553145D02*
X18461D01*
G01D02*
X18467Y1553151D01*
G01D02*
G03X20628Y1554046I0J3056D01*
G01X12569Y1557082D02*
X18892D01*
G01X12569Y1608263D02*
X18299D01*
G01D02*
X18305Y1608269D01*
G01D02*
G02X20731Y1607264I0J-3431D01*
G01X12569Y1604326D02*
X18642D01*
G01D02*
X18648Y1604332D01*
G01D02*
G03X20681Y1605174I0J2875D01*
G01X12569Y1635822D02*
X18355D01*
G01D02*
X18361Y1635828D01*
G01D02*
G03X20464Y1636699I0J2974D01*
G01X12569Y1624011D02*
X18371D01*
G01D02*
X18377Y1624017D01*
G01D02*
G02X20777Y1623023I0J-3394D01*
G01X12569Y1620074D02*
X18524D01*
G01D02*
X18530Y1620080D01*
G01D02*
G03X20683Y1620972I0J3045D01*
G01X12569Y1639759D02*
X18211D01*
G01D02*
X18217Y1639765D01*
G01D02*
G02X20556Y1638796I0J-3308D01*
G01X12569Y1655507D02*
X18560D01*
G01D02*
X18566Y1655513D01*
G01D02*
G02X20555Y1654689I0J-2813D01*
G01X12569Y1651570D02*
X18558D01*
G01D02*
X18564Y1651576D01*
G01D02*
G03X20638Y1652435I0J2933D01*
G01X12569Y1671255D02*
X12575Y1671261D01*
G01D02*
X20338D01*
G01X19560Y1667324D02*
X12575D01*
G01D02*
X12569Y1667318D01*
G01X18881Y387795D02*
G02X20849Y386980I0J-2783D01*
G01D02*
G03X22109Y386458I1260J1260D01*
G01D02*
X24199D01*
G01D02*
G03X25785Y387115I0J2243D01*
G01D02*
X26299Y387629D01*
G01Y383854D02*
X26540Y384094D01*
G01D02*
G03X26099Y385158I-441J441D01*
G01D02*
X22182D01*
G01D02*
G03X21068Y384696I0J-1574D01*
G01D02*
X21067D01*
G01D02*
G02X19044Y383858I-2023J2023D01*
G01X20451Y402781D02*
G03X21839Y402206I1388J1388D01*
G01D02*
X25402D01*
G01D02*
G03X25709Y402333I0J434D01*
G01D02*
G03X26299Y403376I-627J1043D01*
G01Y399601D02*
Y400009D01*
G01D02*
G03X25402Y400906I-897J0D01*
G01D02*
X22096D01*
G01D02*
G03X20842Y400386I1J-1774D01*
G01D02*
X20841D01*
G01D02*
G02X18958Y399606I-1883J1883D01*
G01X21398Y425650D02*
G03X21608Y425466I1453J1447D01*
G01D02*
G03X22612Y425050I1004J1004D01*
G01D02*
X24854D01*
G01D02*
G03X26524Y426720I0J1670D01*
G01X26399Y423322D02*
G03X25366Y423750I-1033J-1033D01*
G01D02*
X22294D01*
G01D02*
G03X21642Y423480I0J-922D01*
G01D02*
G02X21036Y423229I-606J606D01*
G01X19037Y442909D02*
X19043Y442915D01*
G01D02*
G02X20868Y442159I0J-2581D01*
G01D02*
G03X22271Y441578I1403J1403D01*
G01D02*
X24999D01*
G01D02*
G03X26599Y442749I0J1679D01*
G01X19018Y438972D02*
X19024Y438978D01*
G01D02*
G03X20999Y439796I0J2793D01*
G01D02*
G02X22163Y440278I1164J-1164D01*
G01D02*
X24999D01*
G01D02*
G02X26492Y439350I0J-1665D01*
G01X20476Y457818D02*
G03X21664Y457326I1188J1188D01*
G01D02*
X24999D01*
G01D02*
G03X26073Y457771I0J1519D01*
G01D02*
X26799Y458497D01*
G01X20493Y455559D02*
G02X21620Y456026I1127J-1127D01*
G01D02*
X25723D01*
G01D02*
G02X26899Y454850I0J-1176D01*
G01X19482Y474405D02*
X19488Y474411D01*
G01D02*
G02X20965Y473799I0J-2089D01*
G01D02*
G03X22715Y473074I1750J1750D01*
G01D02*
X59426D01*
G01X19413Y470468D02*
X19419Y470474D01*
G01D02*
G03X20872Y471076I0J2055D01*
G01D02*
X21172Y471376D01*
G01D02*
G02X22133Y471774I961J-961D01*
G01D02*
X61675D01*
G01X18956Y490153D02*
X18962Y490159D01*
G01D02*
G02X20980Y489323I0J-2854D01*
G01D02*
G03X22141Y488842I1161J1161D01*
G01D02*
X62293D01*
G01X20711Y487033D02*
G02X21940Y487542I1229J-1229D01*
G01D02*
X61653D01*
G01X20455Y505088D02*
G03X21706Y504570I1251J1251D01*
G01D02*
X25228D01*
G01D02*
G03X26399Y505741I0J1171D01*
G01X20585Y502869D02*
G02X21553Y503270I968J-968D01*
G01D02*
X25095D01*
G01D02*
G02X26399Y501966I0J-1304D01*
G01X18908Y521649D02*
X18914Y521655D01*
G01D02*
G02X21099Y520750I0J-3090D01*
G01D02*
G03X22142Y520318I1043J1043D01*
G01D02*
X28029D01*
G01D02*
G03X28270Y520559I0J241D01*
G01D02*
G02X28511Y520800I241J0D01*
G01D02*
X30429D01*
G01D02*
G02X30670Y520559I0J-241D01*
G01D02*
G03X30911Y520318I241J0D01*
G01D02*
X34499D01*
G01D02*
G03X36499Y521550I0J2239D01*
G01X19254Y517712D02*
X19260Y517718D01*
G01D02*
G03X20931Y518410I0J2363D01*
G01D02*
G03X21199Y518650I-2029J2535D01*
G01D02*
G02X21913Y519005I887J-889D01*
G01D02*
G02X22087Y519018I180J-1243D01*
G01D02*
X34499D01*
G01D02*
G02X36499Y517775I0J-2231D01*
G01X19135Y537397D02*
X19141Y537403D01*
G01D02*
G02X21485Y536432I0J-3315D01*
G01D02*
G03X22369Y536066I884J884D01*
G01D02*
X35796D01*
G01D02*
G03X36188Y536458I0J392D01*
G01D02*
G02X36580Y536850I392J0D01*
G01D02*
X38196D01*
G01D02*
G02X38588Y536458I0J-392D01*
G01D02*
G03X38980Y536066I392J0D01*
G01D02*
X40596D01*
G01X58516Y534766D02*
X23469D01*
G01D02*
G03X21499Y533950I0J-2786D01*
G01D02*
G02X20331Y533466I-1168J1168D01*
G01X20527Y571986D02*
G03X21703Y571499I1176J1176D01*
G01D02*
X72818D01*
G01X20877Y569891D02*
G02X21621Y570199I744J-744D01*
G01D02*
X72819D01*
G01X20471Y623114D02*
G03X21519Y622680I1048J1048D01*
G01D02*
X25161D01*
G01D02*
G03X27143Y623501I-1J2804D01*
G01X20486Y620968D02*
G02X21481Y621380I995J-995D01*
G01D02*
X24657D01*
G01D02*
G02X27499Y620203I0J-4019D01*
G01X20446Y638880D02*
G03X21540Y638427I1094J1094D01*
G01D02*
X24100D01*
G01D02*
G03X26304Y639340I0J3117D01*
G01D02*
X26568Y639604D01*
G01X20445Y636685D02*
G02X21512Y637127I1067J-1067D01*
G01D02*
X24100D01*
G01D02*
G02X26304Y636214I0J-3117D01*
G01D02*
X26568Y635950D01*
G01X27143Y623501D02*
X27499Y623857D01*
G01X20470Y654611D02*
G03X21520Y654176I1050J1050D01*
G01D02*
X25596D01*
G01D02*
G03X26499Y654550I0J1277D01*
G01D02*
G03X26999Y655757I-1207J1207D01*
G01D02*
Y656550D01*
G01X20441Y652431D02*
G02X21515Y652876I1074J-1074D01*
G01D02*
X24518D01*
G01D02*
G02X26737Y651957I0J-3138D01*
G01X19494Y671255D02*
X19500Y671261D01*
G01D02*
G02X20271Y670941I-1J-1091D01*
G01D02*
X20725Y670488D01*
G01D02*
G03X22087Y669924I1362J1362D01*
G01D02*
X24999D01*
G01D02*
G03X27579Y670992I1J3648D01*
G01D02*
X27687Y671101D01*
G01X20196Y667954D02*
G02X21024Y668483I1617J-1619D01*
G01D02*
X21028Y668484D01*
G01D02*
G02X21813Y668624I786J-2138D01*
G01D02*
X24999D01*
G01D02*
G02X27579Y667556I1J-3648D01*
G01D02*
X27687Y667447D01*
G01X19600Y687009D02*
G02X20268Y686733I1J-944D01*
G01D02*
X20600Y686400D01*
G01D02*
X20943Y686058D01*
G01D02*
G03X21591Y685789I649J648D01*
G01D02*
X23641D01*
G01D02*
G03X27650Y687449I1J5668D01*
G01X18894Y683066D02*
X18900Y683072D01*
G01D02*
G03X20073Y683558I0J1659D01*
G01D02*
X20640Y684125D01*
G01D02*
G02X21134Y684427I877J-880D01*
G01D02*
G02X21519Y684489I388J-1181D01*
G01D02*
X23642D01*
G01D02*
G03X28569Y686530I0J6968D01*
G01D02*
X37319Y695280D01*
G01X19594Y687003D02*
X19600Y687009D01*
G01X27650Y687449D02*
X27649D01*
G01D02*
X36399Y696199D01*
G01D02*
X36400D01*
G01D02*
G02X40990Y698100I4589J-4589D01*
G01X37319Y695280D02*
G02X40989Y696800I3670J-3670D01*
G01X97079Y1010130D02*
X34670Y1072539D01*
G01X31820Y1071569D02*
X95651Y1007738D01*
G01X30900Y1070649D02*
X94731Y1006818D01*
G01X34670Y1072539D02*
G02X31974Y1079050I6511J6510D01*
G01D02*
Y1382367D01*
G01X97999Y1011050D02*
X35590Y1073459D01*
G01D02*
G02X33274Y1079050I5591J5591D01*
G01D02*
Y1382368D01*
G01X29574Y1380050D02*
Y1076989D01*
G01D02*
G03X31820Y1071569I7666J1D01*
G01X28274Y1094179D02*
Y1076989D01*
G01D02*
G03X30900Y1070649I8966J0D01*
G01X43709Y1074501D02*
G02X39547Y1084549I10049J10048D01*
G01D02*
Y1394698D01*
G01X36999Y1394318D02*
Y1081050D01*
G01D02*
G03X39474Y1075075I8450J0D01*
G01D02*
X46499Y1068050D01*
G01X35699Y1394317D02*
Y1081050D01*
G01D02*
G03X38554Y1074155I9750J-1D01*
G01D02*
X45579Y1067130D01*
G01X28274Y1183622D02*
Y1097253D01*
G01D02*
G02X27937Y1096916I-337J0D01*
G01D02*
G03X27600Y1096579I0J-337D01*
G01D02*
Y1094853D01*
G01D02*
G03X27937Y1094516I337J0D01*
G01D02*
G02X28274Y1094179I0J-337D01*
G01Y1328751D02*
Y1191496D01*
G01D02*
G02X27937Y1191159I-337J0D01*
G01D02*
X27936D01*
G01D02*
G03X27599Y1190822I0J-337D01*
G01D02*
Y1189096D01*
G01D02*
G03X27936Y1188759I337J0D01*
G01D02*
X27937D01*
G01D02*
G02X28274Y1188422I0J-337D01*
G01D02*
Y1186696D01*
G01D02*
G02X27937Y1186359I-337J0D01*
G01D02*
X27936D01*
G01D02*
G03X27599Y1186022I0J-337D01*
G01D02*
Y1184296D01*
G01D02*
G03X27936Y1183959I337J0D01*
G01D02*
X27937D01*
G01D02*
G02X28274Y1183622I0J-337D01*
G01Y1380051D02*
Y1336625D01*
G01D02*
G02X27937Y1336288I-337J0D01*
G01D02*
G03X27600Y1335951I0J-337D01*
G01D02*
Y1334225D01*
G01D02*
G03X27937Y1333888I337J0D01*
G01D02*
G02X28274Y1333551I0J-337D01*
G01D02*
Y1331825D01*
G01D02*
G02X27937Y1331488I-337J0D01*
G01D02*
G03X27600Y1331151I0J-337D01*
G01D02*
Y1329425D01*
G01D02*
G03X27937Y1329088I337J0D01*
G01D02*
G02X28274Y1328751I0J-337D01*
G01X20262Y1371295D02*
G03X21674Y1370710I1412J1412D01*
G01D02*
X23322D01*
G01D02*
G03X24773Y1371311I0J2052D01*
G01D02*
X25507Y1372045D01*
G01X19025Y1368104D02*
X19031Y1368110D01*
G01D02*
G03X20719Y1368809I0J2387D01*
G01D02*
X20910Y1369001D01*
G01D02*
G02X21899Y1369410I988J-989D01*
G01D02*
X23233D01*
G01D02*
G02X25558Y1368447I0J-3288D01*
G01X31974Y1382367D02*
G03X31195Y1384246I-2656J0D01*
G01D02*
X31044Y1384397D01*
G01D02*
X31042Y1384402D01*
G01D02*
X30384Y1385061D01*
G01X33274Y1382368D02*
G03X32115Y1385166I-3957J0D01*
G01X26489Y1384924D02*
X26681Y1384733D01*
G01D02*
X28309Y1383105D01*
G01D02*
G02X29574Y1380050I-3056J-3055D01*
G01X19028Y1383852D02*
X19034Y1383858D01*
G01D02*
G03X20719Y1384556I0J2383D01*
G01D02*
X21052Y1384889D01*
G01X22872Y1385157D02*
G02X25510Y1384065I1J-3730D01*
G01D02*
X25512Y1384062D01*
G01D02*
X27389Y1382185D01*
G01D02*
G02X28273Y1380050I-2136J-2135D01*
G01D02*
X28274Y1380051D01*
G01X30384Y1385061D02*
G02X29628Y1386937I1951J1877D01*
G01D02*
Y1389054D01*
G01D02*
G03X29445Y1389972I-2400J-1D01*
G01D02*
X29103Y1390799D01*
G01D02*
G03X28727Y1391050I-376J-156D01*
G01D02*
X28499D01*
G01X32115Y1385166D02*
X32113Y1385168D01*
G01D02*
X32111Y1385172D01*
G01D02*
X31314Y1385970D01*
G01D02*
G02X30928Y1386938I1021J968D01*
G01D02*
Y1387550D01*
G01D02*
G02X31231Y1388280I1033J-1D01*
G01D02*
X32333Y1389383D01*
G01X20522Y1386852D02*
G03X21476Y1386457I954J954D01*
G01D02*
X22872D01*
G01D02*
G02X26489Y1384924I1J-5030D01*
G01X21052Y1384889D02*
G02X21699Y1385157I647J-647D01*
G01D02*
X22872D01*
G01X39547Y1394698D02*
G03X37965Y1398517I-5401J0D01*
G01D02*
X31198Y1405284D01*
G01D02*
G02X30199Y1407697I2415J2413D01*
G01X40847Y1394699D02*
G03X38884Y1399436I-6701J-2D01*
G01D02*
X38885Y1399437D01*
G01D02*
X32118Y1406204D01*
G01X26712Y1408515D02*
G02X27799Y1405887I-2628J-2626D01*
G01D02*
Y1405051D01*
G01D02*
G03X27985Y1404603I634J0D01*
G01D02*
X36100Y1396488D01*
G01D02*
G02X36999Y1394318I-2170J-2170D01*
G01X25792Y1407595D02*
G02X26499Y1405888I-1707J-1707D01*
G01D02*
Y1405050D01*
G01D02*
G03X27066Y1403683I1934J1D01*
G01D02*
X27555Y1403193D01*
G01D02*
X34804Y1395945D01*
G01D02*
Y1395944D01*
G01D02*
X35180Y1395568D01*
G01D02*
G02X35699Y1394317I-1250J-1252D01*
G01X36916Y1408751D02*
G03X38174Y1405714I4295J0D01*
G01D02*
X42678Y1401210D01*
G01X35616Y1408750D02*
G03X37255Y1404795I5595J1D01*
G01D02*
X37254Y1404794D01*
G01D02*
X42008Y1400041D01*
G01X30199Y1407697D02*
Y1409050D01*
G01D02*
G03X29280Y1411269I-3138J0D01*
G01D02*
X28999Y1411550D01*
G01X32118Y1406204D02*
G02X31499Y1407698I1494J1494D01*
G01D02*
Y1409170D01*
G01D02*
G02X32451Y1411468I3250J0D01*
G01X20455Y1410594D02*
X20470Y1410578D01*
G01D02*
G03X21205Y1410131I1282J1280D01*
G01D02*
G03X21426Y1410077I540J1730D01*
G01D02*
G03X21751Y1410048I323J1782D01*
G01D02*
X22108D01*
G01D02*
G02X22683Y1409810I0J-813D01*
G01D02*
G03X23311Y1409550I628J628D01*
G01D02*
X24216D01*
G01D02*
G02X25428Y1409335I0J-3521D01*
G01D02*
G02X26712Y1408515I-1217J-3321D01*
G01X19730Y1407481D02*
G03X20329Y1407729I0J847D01*
G01D02*
X20500Y1407900D01*
G01D02*
X21149Y1408548D01*
G01D02*
G02X21635Y1408750I487J-486D01*
G01D02*
G02X22257Y1408492I-1J-880D01*
G01D02*
G03X22841Y1408250I584J584D01*
G01D02*
X24211D01*
G01D02*
G02X25792Y1407595I0J-2237D01*
G01X40768Y1406517D02*
G02X39316Y1410023I3505J3505D01*
G01D02*
Y1415834D01*
G01D02*
G03X38530Y1417732I-2684J0D01*
G01D02*
X32605Y1423657D01*
G01D02*
X32606Y1423658D01*
G01D02*
G02X31199Y1427055I3396J3396D01*
G01D02*
Y1431504D01*
G01X40616Y1415833D02*
G03X39449Y1418651I-3984J1D01*
G01D02*
X39450Y1418652D01*
G01D02*
X33525Y1424577D01*
G01D02*
G02X32499Y1427054I2477J2477D01*
G01D02*
Y1430645D01*
G01X20557Y1426197D02*
G03X21443Y1425830I886J886D01*
G01D02*
X24498D01*
G01D02*
G02X28833Y1424036I2J-6129D01*
G01D02*
X28909Y1423960D01*
G01D02*
X28908Y1423959D01*
G01D02*
X34908Y1417959D01*
G01D02*
X35203Y1417663D01*
G01D02*
X35737Y1417129D01*
G01D02*
X35738D01*
G01D02*
G02X36916Y1414287I-2843J-2844D01*
G01D02*
Y1408751D01*
G01X20634Y1424231D02*
G02X21356Y1424530I722J-722D01*
G01D02*
X24499D01*
G01D02*
G02X27913Y1423116I0J-4828D01*
G01D02*
X34819Y1416210D01*
G01D02*
G02X35616Y1414286I-1924J-1924D01*
G01D02*
Y1408750D01*
G01X31199Y1431504D02*
G03X31017Y1432422I-2400J1D01*
G01D02*
X30661Y1433281D01*
G01D02*
G02X30499Y1434093I1960J813D01*
G01D02*
Y1434550D01*
G01X32499Y1430645D02*
G02X33206Y1432352I2414J0D01*
G01X32915Y1454634D02*
X49083Y1438465D01*
G01X45346Y1432438D02*
X34616Y1443168D01*
G01D02*
Y1443175D01*
G01D02*
X34615Y1443174D01*
G01D02*
X34048Y1443741D01*
G01D02*
X33634Y1444154D01*
G01D02*
G03X31471Y1445050I-2163J-2163D01*
G01D02*
Y1445049D01*
G01D02*
G02X29627Y1447462I1J1912D01*
G01D02*
G03X28989Y1448296I-638J173D01*
G01X46834Y1432794D02*
X34553Y1445074D01*
G01D02*
G03X31472Y1446350I-3082J-3083D01*
G01D02*
G02X31040Y1447393I-1J611D01*
G01D02*
X32094Y1448448D01*
G01X20471Y1442013D02*
G03X21521Y1441578I1050J1050D01*
G01D02*
X31256D01*
G01D02*
G02X33909Y1440480I0J-3754D01*
G01D02*
X42181Y1432207D01*
G01X20535Y1439902D02*
G02X21443Y1440278I908J-908D01*
G01D02*
X31256D01*
G01D02*
G02X32987Y1439561I0J-2448D01*
G01D02*
X41261Y1431287D01*
G01X36498Y1471050D02*
X57337Y1450210D01*
G01X35579Y1470130D02*
X56417Y1449292D01*
G01X42946Y1449998D02*
X30425Y1462518D01*
G01D02*
X30378D01*
G01X54302Y1440481D02*
X39438Y1455345D01*
G01D02*
X38789Y1455993D01*
G01D02*
X38722Y1456060D01*
G01D02*
Y1456061D01*
G01D02*
X34366Y1460417D01*
G01D02*
G02X33915Y1461506I1089J1089D01*
G01D02*
Y1462681D01*
G01X19265Y1458657D02*
X19271Y1458663D01*
G01D02*
G02X21217Y1457857I0J-2752D01*
G01D02*
G03X22504Y1457356I1475J1885D01*
G01D02*
G03X22691Y1457349I183J2386D01*
G01D02*
X29500D01*
G01D02*
G02X33835Y1455554I0J-6132D01*
G01D02*
X33919Y1455470D01*
G01D02*
X33918Y1455469D01*
G01D02*
X49668Y1439719D01*
G01X19202Y1454720D02*
X19208Y1454726D01*
G01D02*
G03X20782Y1455378I0J2226D01*
G01D02*
G02X21597Y1455902I1614J-1615D01*
G01D02*
X21602Y1455904D01*
G01D02*
G02X22402Y1456049I802J-2146D01*
G01D02*
X29499D01*
G01D02*
G02X32915Y1454634I0J-4831D01*
G01X28989Y1448296D02*
X28697D01*
G01X83208Y1443236D02*
X35946Y1490498D01*
G01D02*
X35697Y1490748D01*
G01X83865Y1444417D02*
X36616Y1491667D01*
G01X20978Y1489223D02*
G03X21881Y1488849I903J903D01*
G01D02*
X27316D01*
G01D02*
G03X27541Y1489074I0J225D01*
G01D02*
Y1489075D01*
G01D02*
G02X27766Y1489300I225J0D01*
G01D02*
X29716D01*
G01D02*
G02X29941Y1489075I0J-225D01*
G01D02*
Y1489074D01*
G01D02*
G03X30166Y1488849I225J0D01*
G01D02*
X31656D01*
G01D02*
G02X35999Y1487050I0J-6142D01*
G01D02*
X80453Y1442595D01*
G01X20865Y1487098D02*
G02X21954Y1487549I1089J-1089D01*
G01D02*
X31655D01*
G01D02*
G02X35080Y1486130I0J-4842D01*
G01D02*
X79532Y1441678D01*
G01X59887Y1451056D02*
X34445Y1476497D01*
G01D02*
X33497Y1477445D01*
G01D02*
X33362Y1477581D01*
G01D02*
X32488Y1478455D01*
G01D02*
G02X30999Y1482050I3595J3595D01*
G01X61107Y1451675D02*
X34282Y1478500D01*
G01D02*
X34076Y1478707D01*
G01D02*
X33409Y1479374D01*
G01D02*
G02X32999Y1480364I990J990D01*
G01D02*
G02X34318Y1481683I1319J0D01*
G01D02*
X34465D01*
G01X19377Y1474405D02*
X19383Y1474411D01*
G01D02*
G02X21273Y1473628I0J-2673D01*
G01D02*
G03X22597Y1473079I1324J1322D01*
G01D02*
G03X22599I1J1736D01*
G01D02*
X31600D01*
G01D02*
G02X36498Y1471050I0J-6927D01*
G01X19241Y1470468D02*
X19247Y1470474D01*
G01D02*
G03X21000Y1471200I0J2479D01*
G01D02*
G02X21381Y1471477I1073J-1075D01*
G01D02*
X21602Y1471591D01*
G01D02*
G02X22380Y1471779I778J-1516D01*
G01D02*
X31599D01*
G01D02*
G02X35579Y1470130I0J-5627D01*
G01X41586Y1505698D02*
G03X38499Y1506976I-3086J-3087D01*
G01D02*
X36127D01*
G01D02*
G02X32724Y1508385I0J4813D01*
G01D02*
X32149Y1508961D01*
G01D02*
G02X31386Y1510802I1840J1841D01*
G01D02*
G03X30288Y1511900I-1098J0D01*
G01X42507Y1506617D02*
G03X38499Y1508275I-4005J-4007D01*
G01D02*
Y1508276D01*
G01D02*
X36128D01*
G01D02*
G02X33644Y1509305I0J3513D01*
G01D02*
X33068Y1509881D01*
G01D02*
G02X32686Y1510802I919J921D01*
G01D02*
Y1511225D01*
G01D02*
G02X33512Y1512051I826J0D01*
G01X20724Y1504955D02*
G03X21653Y1504570I929J929D01*
G01D02*
X36768D01*
G01D02*
G02X41120Y1502768I1J-6153D01*
G01X20751Y1502913D02*
G02X21613Y1503270I862J-862D01*
G01D02*
X36768D01*
G01D02*
G02X40200Y1501849I1J-4853D01*
G01X35697Y1490748D02*
X35453Y1491004D01*
G01D02*
G03X34087Y1491686I-2362J-3022D01*
G01D02*
X34086Y1491684D01*
G01D02*
G02X34084Y1491685I1227J2457D01*
G01D02*
G02X32899Y1492355I717J2651D01*
G01D02*
X32886Y1492366D01*
G01D02*
X32850Y1492401D01*
G01D02*
X32600Y1492651D01*
G01D02*
G02X31649Y1494950I2300J2297D01*
G01D02*
Y1495550D01*
G01D02*
G03X31048Y1497001I-2052J0D01*
G01D02*
X30499Y1497550D01*
G01X36616Y1491667D02*
X36253Y1492029D01*
G01D02*
G03X34423Y1492941I-3160J-4049D01*
G01D02*
G02X33777Y1493315I377J1396D01*
G01D02*
X33770Y1493321D01*
G01D02*
X33520Y1493571D01*
G01D02*
G02X32949Y1494950I1379J1379D01*
G01D02*
Y1495550D01*
G01D02*
G02X33550Y1497001I2052J0D01*
G01D02*
X34099Y1497550D01*
G01X30288Y1511900D02*
X30115D01*
G01X19210Y1521649D02*
X19216Y1521655D01*
G01D02*
G02X20930Y1520945I0J-2424D01*
G01D02*
G03X22444Y1520318I1514J1514D01*
G01D02*
X29999D01*
G01D02*
G03X31396Y1520896I1J1975D01*
G01D02*
X31999Y1521500D01*
G01X19231Y1517712D02*
X19237Y1517718D01*
G01D02*
G03X20826Y1518376I0J2247D01*
G01D02*
G02X21947Y1518975I1549J-1551D01*
G01D02*
G02X22376Y1519018I432J-2149D01*
G01D02*
X29999D01*
G01D02*
G02X30298Y1518995I-3J-1999D01*
G01D02*
G02X31416Y1518429I-304J-1987D01*
G01D02*
X31999Y1517846D01*
G01X42528Y1543532D02*
X30266Y1555794D01*
G01X43424Y1544476D02*
X32174Y1555726D01*
G01X26721Y1554668D02*
X40798Y1540591D01*
G01X24104Y1554451D02*
G02X25801Y1553748I0J-2400D01*
G01D02*
X39878Y1539671D01*
G01D02*
G02X40581Y1537974I-1697J-1697D01*
G01X30266Y1555794D02*
G02X28049Y1561050I5121J5255D01*
G01D02*
Y1569550D01*
G01D02*
G03X27123Y1572205I-4269J0D01*
G01X32174Y1555726D02*
G03X31174Y1556725I-999000J-999000D01*
G01D02*
G02X29349Y1561050I4212J4325D01*
G01D02*
Y1569550D01*
G01D02*
G02X30520Y1572049I3252J0D01*
G01X18892Y1557082D02*
X18898Y1557088D01*
G01D02*
G02X21131Y1556163I0J-3158D01*
G01D02*
G03X22126Y1555751I995J995D01*
G01D02*
X24104D01*
G01D02*
G02X26721Y1554668I1J-3700D01*
G01X20628Y1554046D02*
G02X21606Y1554451I978J-978D01*
G01D02*
X24104D01*
G01X324499Y1609417D02*
X32734D01*
G01D02*
G02X29999Y1610550I0J3868D01*
G01D02*
G02X28899Y1613206I2656J2656D01*
G01D02*
Y1613524D01*
G01X324500Y1610717D02*
X32735D01*
G01D02*
G02X30919Y1611470I0J2567D01*
G01D02*
G02X30878Y1611513I1756J1715D01*
G01D02*
G02X30895Y1612446I492J458D01*
G01D02*
X31743Y1613293D01*
G01D02*
G02X32299Y1613524I557J-556D01*
G01X20731Y1607264D02*
X20732Y1607263D01*
G01D02*
G03X21656Y1606851I999J998D01*
G01D02*
G03X21733Y1606849I75J1415D01*
G01D02*
X322999D01*
G01X20681Y1605174D02*
G02X21586Y1605549I905J-905D01*
G01D02*
X322999D01*
G01X20556Y1638796D02*
G03X21444Y1638428I888J888D01*
G01D02*
X38936D01*
G01D02*
G03X42249Y1639801I0J4684D01*
G01X20464Y1636699D02*
G02X21500Y1637128I1036J-1036D01*
G01D02*
X38937D01*
G01D02*
G03X43169Y1638881I0J5985D01*
G01X62834Y1652484D02*
X36643Y1626293D01*
G01D02*
G02X34149Y1625260I-2494J2494D01*
G01D02*
X32896D01*
G01D02*
G02X31985Y1625638I1J1289D01*
G01D02*
X31776Y1625846D01*
G01D02*
G02X30906Y1627534I2204J2204D01*
G01D02*
G03X30122Y1629427I-2677J0D01*
G01D02*
X29499Y1630050D01*
G01X62030Y1653519D02*
X35532Y1627021D01*
G01D02*
G02X34419Y1626560I-1113J1113D01*
G01D02*
X33246D01*
G01D02*
G02X32663Y1627143I0J583D01*
G01D02*
Y1628181D01*
G01X20777Y1623023D02*
G03X21605Y1622680I828J828D01*
G01D02*
X72718D01*
G01X20683Y1620972D02*
G02X21668Y1621380I985J-985D01*
G01D02*
X72719D01*
G01X55832Y1660431D02*
X37098Y1641697D01*
G01D02*
G02X35000Y1640828I-2098J2099D01*
G01D02*
X33224D01*
G01D02*
G02X30933Y1641776I-1J3239D01*
G01D02*
G02X30218Y1643226I1772J1775D01*
G01D02*
X30116Y1644007D01*
G01D02*
G03X29626Y1645002I-1708J-223D01*
G01X53055Y1659493D02*
X37055Y1643493D01*
G01D02*
X36178Y1642617D01*
G01D02*
G02X34999Y1642128I-1180J1179D01*
G01D02*
X33224D01*
G01D02*
G02X31853Y1642696I0J1939D01*
G01D02*
G02Y1644404I853J854D01*
G01D02*
X32128Y1644679D01*
G01D02*
G02X33026Y1645051I898J-898D01*
G01X38605Y1659943D02*
X36049Y1657386D01*
G01D02*
G02X35319Y1656862I-1955J1954D01*
G01D02*
G02X34095Y1656576I-1224J2476D01*
G01D02*
X33209D01*
G01D02*
G02X30521Y1657688I-1J3802D01*
G01D02*
X30433Y1657776D01*
G01D02*
Y1657778D01*
G01D02*
G02X29699Y1659546I1773J1772D01*
G01D02*
G02Y1659579I2693J17D01*
G01D02*
G02X29700Y1659630I2693J-27D01*
G01D02*
G03X29496Y1660143I-697J20D01*
G01X47686Y1670863D02*
X35129Y1658306D01*
G01D02*
G02X34743Y1658028I-1037J1033D01*
G01D02*
G02X34700Y1658008I-639J1317D01*
G01D02*
G02X34304Y1657892I-605J1332D01*
G01D02*
G02X34091Y1657876I-216J1448D01*
G01D02*
X33209D01*
G01D02*
G02X31499Y1658552I0J2501D01*
G01D02*
X31353Y1658698D01*
G01D02*
G02X31124Y1659017I853J854D01*
G01D02*
X31123D01*
G01D02*
G02X30999Y1659551I1083J533D01*
G01D02*
G02Y1659568I1393J9D01*
G01D02*
G02X31000Y1659593I1392J-43D01*
G01D02*
G03X30995Y1659809I-1997J62D01*
G01X20555Y1654689D02*
X20556D01*
G01D02*
G03X21793Y1654176I1238J1237D01*
G01D02*
X35697D01*
G01D02*
G03X37465Y1654908I0J2501D01*
G01D02*
X51053Y1668496D01*
G01X20638Y1652435D02*
G02X21703Y1652876I1065J-1065D01*
G01D02*
X35575D01*
G01D02*
G03X38472Y1654076I0J4097D01*
G01D02*
X51972Y1667576D01*
G01X48605Y1669943D02*
X38605Y1659943D01*
G01X29496Y1660143D02*
X28600Y1661039D01*
G01X30995Y1659809D02*
G02X31179Y1660307I633J49D01*
G01D02*
X31999Y1661127D01*
G01X20338Y1671261D02*
G02X20763Y1671085I0J-601D01*
G01D02*
X21198Y1670650D01*
G01D02*
X21199D01*
G01D02*
G03X21926Y1670349I727J727D01*
G01D02*
X23500D01*
G01D02*
G03X24778Y1670879I-1J1808D01*
G01D02*
X25050Y1671150D01*
G01D02*
X36400Y1682500D01*
G01X37319Y1681580D02*
X25697Y1669958D01*
G01D02*
G02X23500Y1669050I-2195J2200D01*
G01D02*
Y1669049D01*
G01D02*
X22589D01*
G01D02*
G03X22235Y1669006I1J-1489D01*
G01D02*
G03X21536Y1668613I353J-1446D01*
G01D02*
X20733Y1667810D01*
G01D02*
G02X19560Y1667324I-1173J1173D01*
G01X40669Y1670329D02*
X36768Y1666428D01*
G01D02*
G02X33799Y1665200I-2967J2970D01*
G01D02*
X32734D01*
G01D02*
G02X30800Y1666001I-1J2734D01*
G01D02*
X30799Y1666000D01*
G01D02*
X30735Y1666064D01*
G01D02*
G02X30100Y1667599I1538J1535D01*
G01D02*
Y1668100D01*
G01D02*
G03X29817Y1668783I-966J0D01*
G01D02*
X29100Y1669500D01*
G01X41200Y1674751D02*
G02X39750Y1671250I-4951J0D01*
G01D02*
X35848Y1667348D01*
G01D02*
G02X33800Y1666500I-2048J2049D01*
G01D02*
X32733D01*
G01D02*
G02X31719Y1666920I0J1434D01*
G01D02*
X31655Y1666984D01*
G01D02*
G02X31400Y1667600I617J616D01*
G01D02*
Y1668100D01*
G01D02*
G02X31762Y1668974I1236J0D01*
G01D02*
X32494Y1669706D01*
G01X36400Y1682500D02*
G03X37500Y1685156I-2656J2656D01*
G01D02*
Y1716131D01*
G01X38800Y1728300D02*
Y1685156D01*
G01D02*
G02X37319Y1681580I-5056J-1D01*
G01X37500Y1716131D02*
G03X37250Y1716381I-250J0D01*
G01D02*
G02X37000Y1716631I0J250D01*
G01D02*
Y1718531D01*
G01D02*
G02X37250Y1718781I250J0D01*
G01D02*
G03X37500Y1719031I0J250D01*
G01D02*
Y1728300D01*
G01D02*
X37501D01*
G01D02*
G02X38941Y1731780I4921J2D01*
G01D02*
X40380Y1733220D01*
G01X41300Y1732300D02*
X39861Y1730860D01*
G01D02*
G03X38800Y1728300I2560J-2561D01*
G01X59426Y473074D02*
G03X59712Y473083I6J4343D01*
G01D02*
G03X62497Y474346I-286J4334D01*
G01X40596Y536066D02*
G03X40988Y536458I0J392D01*
G01D02*
G02X41380Y536850I392J0D01*
G01D02*
X42996D01*
G01D02*
G02X43388Y536458I0J-392D01*
G01D02*
G03X43780Y536066I392J0D01*
G01D02*
X58517D01*
G01D02*
G02X59102Y536015I-2J-3403D01*
G01D02*
Y536016D01*
G01D02*
G03X59999Y536771I131J755D01*
G01D02*
Y537550D01*
G01X60003Y534150D02*
G03X58516Y534766I-1487J-1487D01*
G01X40990Y698100D02*
X47700D01*
G01D02*
G03X50260Y699161I-1J3621D01*
G01D02*
X50300Y699200D01*
G01X40989Y696800D02*
X47998D01*
G01D02*
G02X50410Y695801I0J-3411D01*
G01X120079Y998131D02*
X43709Y1074501D01*
G01X120999Y999051D02*
X44629Y1075421D01*
G01X46499Y1068050D02*
X116877Y997671D01*
G01X45579Y1067130D02*
X115957Y996751D01*
G01X52999Y1072551D02*
X124561Y1000988D01*
G01X52079Y1071631D02*
X123641Y1000068D01*
G01X44629Y1075421D02*
G02X40847Y1084550I9129J9130D01*
G01D02*
Y1394699D01*
G01X126536Y1002512D02*
X54999Y1074050D01*
G01D02*
X49957Y1079092D01*
G01D02*
G02X46947Y1086359I7267J7267D01*
G01D02*
Y1398586D01*
G01X127456Y1003432D02*
X55919Y1074970D01*
G01D02*
X50877Y1080012D01*
G01D02*
G02X48247Y1086359I6347J6348D01*
G01D02*
Y1398587D01*
G01X44547Y1397051D02*
Y1084801D01*
G01D02*
G03X47233Y1078315I9172J-1D01*
G01D02*
X52999Y1072551D01*
G01X43247Y1397050D02*
Y1084801D01*
G01D02*
G03X46313Y1077395I10473J-2D01*
G01D02*
X52079Y1071631D01*
G01X59347Y1091050D02*
G03X61122Y1086768I6055J1D01*
G01D02*
X66918Y1080970D01*
G01X58047Y1091049D02*
G03X60202Y1085848I7356J1D01*
G01D02*
X65998Y1080050D01*
G01X62498Y1078050D02*
X56712Y1083838D01*
G01D02*
G02X54347Y1089546I5708J5709D01*
G01X63418Y1078970D02*
X57632Y1084758D01*
G01D02*
G02X55647Y1089547I4787J4790D01*
G01X51947Y1401364D02*
Y1088050D01*
G01D02*
G03X54385Y1082164I8324J0D01*
G01D02*
X59499Y1077050D01*
G01D02*
X131184Y1005364D01*
G01X50647Y1401363D02*
Y1088050D01*
G01D02*
G03X53465Y1081244I9625J-1D01*
G01D02*
X58579Y1076130D01*
G01D02*
X130264Y1004444D01*
G01X59347Y1403437D02*
Y1091050D01*
G01X58047Y1403436D02*
Y1091049D01*
G01X54347Y1089546D02*
Y1401550D01*
G01X55647Y1089547D02*
Y1401351D01*
G01X46947Y1398586D02*
G03X45708Y1401577I-4230J0D01*
G01D02*
X40767Y1406516D01*
G01X48247Y1398587D02*
G03X46628Y1402497I-5531J0D01*
G01D02*
X46287Y1402838D01*
G01D02*
X46286Y1402837D01*
G01D02*
X41687Y1407436D01*
G01X42678Y1401210D02*
X42679D01*
G01D02*
X42928Y1400961D01*
G01D02*
G02X44547Y1397051I-3912J-3910D01*
G01X42008Y1400041D02*
G02X43247Y1397050I-2991J-2991D01*
G01X57220Y1408570D02*
G02X59347Y1403437I-5134J-5135D01*
G01X56301Y1407650D02*
G02X58047Y1403436I-4215J-4215D01*
G01X54347Y1401550D02*
G03X52353Y1406365I-6810J0D01*
G01X55647Y1401351D02*
G03X53131Y1407425I-8590J0D01*
G01X46885Y1408437D02*
X50126Y1405197D01*
G01D02*
Y1405196D01*
G01D02*
X50522Y1404800D01*
G01D02*
G02X51944Y1401367I-3433J-3433D01*
G01D02*
X51947Y1401364D01*
G01X44716Y1408768D02*
X49207Y1404277D01*
G01D02*
X49604Y1403881D01*
G01D02*
G02X50647Y1401363I-2518J-2518D01*
G01X40767Y1406516D02*
X40768Y1406517D01*
G01X41687Y1407436D02*
G02X40616Y1410022I2586J2586D01*
G01D02*
Y1415833D01*
G01X59681Y1444551D02*
Y1419310D01*
G01D02*
G03X61168Y1415720I5077J0D01*
G01D02*
X63844Y1413044D01*
G01X58381Y1444550D02*
Y1419310D01*
G01D02*
G03X60249Y1414800I6377J-1D01*
G01D02*
X61925Y1413123D01*
G01X61747Y1406310D02*
G03X60579Y1409130I-3988J0D01*
G01D02*
X55712Y1413997D01*
G01D02*
G02X55383Y1414356I3947J3947D01*
G01D02*
G02X54116Y1417839I4148J3481D01*
G01D02*
Y1437789D01*
G01X61498Y1410051D02*
X56621Y1414930D01*
G01D02*
G02X55416Y1417839I2909J2909D01*
G01D02*
Y1433589D01*
G01X51716Y1435249D02*
Y1416415D01*
G01D02*
G03X53370Y1412422I5647J0D01*
G01D02*
X53371Y1412423D01*
G01D02*
X54290Y1411503D01*
G01D02*
X54289Y1411502D01*
G01D02*
X57221Y1408571D01*
G01D02*
X57220Y1408570D01*
G01X50416Y1435250D02*
Y1416414D01*
G01D02*
G03X52451Y1411503I6947J1D01*
G01D02*
X52450Y1411502D01*
G01D02*
X56301Y1407651D01*
G01D02*
Y1407650D01*
G01X52353Y1406365D02*
X48083Y1410635D01*
G01D02*
X48084Y1410636D01*
G01D02*
G02X46716Y1413939I3302J3302D01*
G01D02*
Y1429938D01*
G01X53131Y1407425D02*
X49003Y1411555D01*
G01D02*
G02X48016Y1413938I2383J2383D01*
G01D02*
Y1429939D01*
G01X42181Y1432207D02*
G02X44316Y1427049I-5157J-5156D01*
G01D02*
Y1412875D01*
G01D02*
G03X45635Y1409691I4503J0D01*
G01D02*
X46046Y1409280D01*
G01D02*
X46045Y1409279D01*
G01D02*
X46885Y1408437D01*
G01X41261Y1431287D02*
G02X43016Y1427050I-4237J-4237D01*
G01D02*
Y1412872D01*
G01D02*
G03X44716Y1408768I5804J0D01*
G01X57337Y1450210D02*
G02X59681Y1444551I-5659J-5659D01*
G01X56417Y1449292D02*
G02X58381Y1444550I-4742J-4742D01*
G01X54116Y1437789D02*
G03X53382Y1439561I-2506J0D01*
G01D02*
X42946Y1449998D01*
G01X55416Y1433589D02*
X55421Y1433594D01*
G01D02*
Y1434670D01*
G01D02*
X55416Y1434675D01*
G01D02*
Y1437790D01*
G01D02*
G03X54301Y1440480I-3806J-1D01*
G01D02*
X54302Y1440481D01*
G01X49668Y1439719D02*
X50003Y1439385D01*
G01D02*
G02X51716Y1435249I-4136J-4136D01*
G01X49083Y1438465D02*
X49084Y1438466D01*
G01D02*
G02X50415Y1435249I-3218J-3215D01*
G01D02*
X50416Y1435250D01*
G01X46716Y1429938D02*
G03X45914Y1431874I-2738J0D01*
G01D02*
X45350Y1432438D01*
G01D02*
X45346D01*
G01X48016Y1429939D02*
G03X46834Y1432794I-4039J0D01*
G01X62081Y1446335D02*
G03X60294Y1450650I-6103J0D01*
G01D02*
X60188Y1450756D01*
G01D02*
X59887Y1451056D01*
G01X61214Y1451570D02*
X61108Y1451676D01*
G01D02*
X61107Y1451675D01*
G01X91505Y1455778D02*
X41866Y1505417D01*
G01X92285Y1456836D02*
X42787Y1506335D01*
G01X41120Y1502768D02*
X88394Y1455494D01*
G01X40649Y1501399D02*
X87474Y1454574D01*
G01X98829Y1462881D02*
X48416Y1513294D01*
G01X99749Y1463800D02*
X49335Y1514214D01*
G01X43918Y1512970D02*
X95918Y1460970D01*
G01X42999Y1512050D02*
X94999Y1460050D01*
G01X41866Y1505417D02*
X41586Y1505698D01*
G01X42787Y1506335D02*
X42507Y1506617D01*
G01X40200Y1501849D02*
Y1501847D01*
G01D02*
X40648Y1501399D01*
G01D02*
X40649D01*
G01X48416Y1513294D02*
G02X46317Y1518362I5067J5067D01*
G01D02*
Y1521470D01*
G01D02*
X46318Y1521471D01*
G01D02*
Y1535050D01*
G01X49335Y1514214D02*
G02X47617Y1518362I4148J4148D01*
G01D02*
Y1520931D01*
G01D02*
X47618Y1520932D01*
G01D02*
Y1535050D01*
G01X41881Y1537974D02*
Y1517888D01*
G01D02*
G03X43918Y1512970I6955J0D01*
G01X40581Y1537974D02*
Y1517888D01*
G01D02*
G03X42999Y1512050I8255J-1D01*
G01X46318Y1535050D02*
G03X42554Y1543510I-11389J0D01*
G01D02*
X42528Y1543532D01*
G01X47618Y1535050D02*
G03X43424Y1544476I-12689J0D01*
G01X40798Y1540591D02*
G02X41881Y1537974I-2617J-2616D01*
G01X55225Y1661662D02*
X53055Y1659493D01*
G01X42249Y1639801D02*
X58499Y1656050D01*
G01D02*
X59479Y1657028D01*
G01D02*
G03X60949Y1660577I-3549J3549D01*
G01X43169Y1638881D02*
X59418Y1655130D01*
G01D02*
X60398Y1656108D01*
G01D02*
G03X62249Y1660581I-4474J4471D01*
G01X58549Y1813371D02*
Y1666550D01*
G01D02*
G02X56143Y1660743I-8213J1D01*
G01D02*
X55832Y1660431D01*
G01X57249Y1813372D02*
Y1666550D01*
G01D02*
G02X55225Y1661662I-6912J-1D01*
G01X60949Y1660577D02*
Y1811238D01*
G01X51149Y1847652D02*
Y1675786D01*
G01D02*
G02X48816Y1670155I-7962J0D01*
G01D02*
X48605Y1669943D01*
G01X49849Y1847652D02*
Y1675786D01*
G01D02*
G02X47897Y1671075I-6663J1D01*
G01D02*
X47686Y1670863D01*
G01X51053Y1668496D02*
G03X53549Y1674522I-6026J6026D01*
G01D02*
Y1846237D01*
G01X51972Y1667576D02*
G03X54849Y1674522I-6946J6946D01*
G01D02*
Y1846236D01*
G01X42500Y1724393D02*
Y1674752D01*
G01D02*
G02X40669Y1670331I-6251J-1D01*
G01D02*
Y1670329D01*
G01X41200Y1724394D02*
Y1674751D01*
G01X40380Y1733220D02*
G02X42506Y1734100I2126J-2128D01*
G01D02*
X43900D01*
G01D02*
G03X44400Y1734600I0J500D01*
G01D02*
Y1735700D01*
G01D02*
G03X43976Y1736724I-1449J0D01*
G01D02*
X43600Y1737100D01*
G01X47000D02*
X46195Y1736295D01*
G01D02*
G03X45700Y1735100I1195J-1195D01*
G01D02*
Y1734600D01*
G01D02*
G02X43900Y1732800I-1800J0D01*
G01D02*
X42507D01*
G01D02*
G03X41300Y1732300I0J-1707D01*
G01X45877Y1724823D02*
X45195Y1725505D01*
G01D02*
G03X44000Y1726000I-1195J-1195D01*
G01D02*
X43966D01*
G01D02*
G03X43000Y1725600I0J-1366D01*
G01D02*
G03X42500Y1724393I1207J-1207D01*
G01X45877Y1728477D02*
X45195Y1727795D01*
G01D02*
G02X44000Y1727300I-1195J1195D01*
G01D02*
X43966D01*
G01D02*
G03X42080Y1726519I0J-2667D01*
G01D02*
G03X41200Y1724394I2125J-2125D01*
G01X64832Y1821778D02*
X60051Y1816997D01*
G01D02*
G03X58549Y1813371I3626J-3626D01*
G01X63912Y1822697D02*
X59131Y1817916D01*
G01D02*
G03X57249Y1813372I4546J-4545D01*
G01X60949Y1811238D02*
G02X62444Y1815446I6671J0D01*
G01X53418Y1853130D02*
G03X51149Y1847652I5478J-5478D01*
G01X52499Y1854050D02*
G03X49849Y1847652I6397J-6397D01*
G01X53549Y1846237D02*
G02X56115Y1852432I8763J-1D01*
G01X54849Y1846236D02*
G02X57035Y1851513I7463J0D01*
G01X62475Y1860250D02*
G03X59168Y1858880I0J-4677D01*
G01D02*
X53418Y1853130D01*
G01X62474Y1861550D02*
G03X58249Y1859799I2J-5977D01*
G01D02*
X58248D01*
G01D02*
X52499Y1854050D01*
G01X56115Y1852432D02*
X58615Y1854932D01*
G01D02*
X58616D01*
G01D02*
G02X62841Y1856683I4227J-4226D01*
G01X57035Y1851513D02*
X59535Y1854013D01*
G01D02*
G02X62842Y1855383I3307J-3307D01*
G01X95899Y119694D02*
X81615D01*
G01D02*
G02X81221Y119857I0J557D01*
G01D02*
G03X79458Y120498I-1763J-2104D01*
G01D02*
X79445Y120511D01*
G01D02*
X77166D01*
G01X95899Y118394D02*
X81629D01*
G01D02*
G03X80799Y118050I0J-1174D01*
G01D02*
G02X79107Y117349I-1692J1692D01*
G01D02*
X79094Y117362D01*
G01D02*
X77166D01*
G01X84499Y127843D02*
X81629D01*
G01D02*
G03X80799Y127499I0J-1174D01*
G01D02*
G02X79107Y126798I-1692J1692D01*
G01D02*
X79094Y126811D01*
G01D02*
X77166D01*
G01X85499Y129143D02*
X81615D01*
G01D02*
G02X81221Y129306I0J557D01*
G01D02*
G03X79458Y129947I-1763J-2104D01*
G01D02*
X79445Y129960D01*
G01D02*
X77166D01*
G01X61675Y471774D02*
G02X62503Y470946I0J-828D01*
G01X62293Y488842D02*
G03X63067Y489616I0J774D01*
G01X61653Y487542D02*
G02X62978Y486217I0J-1325D01*
G01X99655Y525350D02*
X82194D01*
G01D02*
G02X81702Y525554I0J696D01*
G01D02*
G03X80179Y526010I-1522J-2313D01*
G01D02*
X80166Y526023D01*
G01D02*
X77166D01*
G01X83475Y524029D02*
G03X82099Y523350I314J-2369D01*
G01D02*
G02X80918Y522861I-1181J1181D01*
G01D02*
X80905Y522874D01*
G01D02*
X77166D01*
G01X82703Y533150D02*
G03X81708Y532738I0J-1407D01*
G01D02*
G02X80675Y532310I-1033J1033D01*
G01D02*
X80662Y532323D01*
G01D02*
X77166D01*
G01X82809Y534450D02*
G02X81677Y534919I0J1601D01*
G01D02*
G03X80373Y535459I-1304J-1304D01*
G01D02*
X80360Y535472D01*
G01D02*
X77166D01*
G01X72818Y571499D02*
G03X76729Y573119I0J5531D01*
G01D02*
X84229Y580619D01*
G01X72819Y570199D02*
G03X77648Y572199I-1J6831D01*
G01D02*
X85149Y579700D01*
G01X84299Y653750D02*
X79699Y658350D01*
G01D02*
G02X78694Y659996I2896J2898D01*
G01D02*
X78687Y660019D01*
G01D02*
G02X78469Y661402I4286J1384D01*
G01D02*
G03X78188Y662674I-5068J-453D01*
G01D02*
G03X76999Y664550I-4789J-1720D01*
G01X85219Y654669D02*
X80619Y659269D01*
G01D02*
Y659270D01*
G01D02*
G02X79977Y660267I1977J1978D01*
G01D02*
Y660268D01*
G01D02*
G02X79932Y660393I2608J1009D01*
G01D02*
G02X79816Y660947I2666J847D01*
G01D02*
X79680Y662237D01*
G01D02*
G02X79752Y663237I2833J299D01*
G01D02*
G02X80499Y664550I2761J-702D01*
G01X83421Y930389D02*
G02X82038Y930962I0J1956D01*
G01D02*
G03X80655Y931535I-1383J-1383D01*
G01D02*
X77166D01*
G01Y928386D02*
X81048D01*
G01D02*
G03X82328Y928765I0J2351D01*
G01X82994Y938750D02*
G03X82149Y938400I0J-1195D01*
G01D02*
G02X80754Y937822I-1395J1395D01*
G01D02*
X80741Y937835D01*
G01D02*
X77166D01*
G01X82839Y940117D02*
G02X82146Y940404I0J980D01*
G01D02*
X82099Y940450D01*
G01D02*
G03X80841Y940971I-1258J-1258D01*
G01D02*
X80828Y940984D01*
G01D02*
X77166D01*
G01X66918Y1080970D02*
X138274Y1009614D01*
G01X65998Y1080050D02*
X137354Y1008694D01*
G01X133867Y1006681D02*
X62498Y1078050D01*
G01X134787Y1007601D02*
X63418Y1078970D01*
G01X124615Y1038167D02*
X71615Y1091167D01*
G01X125723Y1038899D02*
X72535Y1092087D01*
G01X68668Y1090220D02*
X133521Y1025367D01*
G01X67748Y1089300D02*
X132601Y1024447D01*
G01X141249Y1010300D02*
X66999Y1084550D01*
G01D02*
X63689Y1087859D01*
G01D02*
G02X61747Y1092549I4690J4689D01*
G01X142169Y1011220D02*
X67919Y1085470D01*
G01D02*
X64609Y1088779D01*
G01X71615Y1091167D02*
X71616Y1091168D01*
G01D02*
G02X69599Y1096038I4869J4869D01*
G01D02*
Y1209859D01*
G01X72535Y1092087D02*
G02X70899Y1096037I3950J3950D01*
G01D02*
Y1209858D01*
G01X67199Y1215334D02*
Y1093766D01*
G01D02*
G03X68668Y1090220I5015J0D01*
G01X65899Y1215335D02*
Y1093765D01*
G01D02*
G03X67748Y1089300I6316J0D01*
G01X61747Y1092549D02*
Y1406310D01*
G01X64609Y1088779D02*
G02X63048Y1092549I3771J3769D01*
G01D02*
X63047Y1092548D01*
G01D02*
Y1406309D01*
G01X69599Y1209859D02*
G02X71530Y1214519I6592J-1D01*
G01D02*
X71528D01*
G01D02*
G02X71529Y1214520I4662J-4661D01*
G01D02*
X80504Y1223495D01*
G01X70899Y1209858D02*
G02X72449Y1213600I5292J0D01*
G01D02*
X81424Y1222575D01*
G01X68668Y1218880D02*
G03X67199Y1215334I3546J-3546D01*
G01X67748Y1219799D02*
G03X65899Y1215335I4466J-4465D01*
G01X80504Y1223495D02*
G03X85900Y1236522I-13027J13027D01*
G01X81424Y1222575D02*
G03X87200Y1236519I-13944J13944D01*
G01X76184Y1238866D02*
G02X77434Y1235848I-3018J-3018D01*
G01D02*
X77490Y1235057D01*
G01D02*
X77499Y1235050D01*
G01D02*
Y1230549D01*
G01D02*
G02X75493Y1225704I-6854J0D01*
G01D02*
X75419Y1225630D01*
G01D02*
X75418D01*
G01D02*
X68668Y1218880D01*
G01X75264Y1237946D02*
G02X76134Y1235848I-2098J-2099D01*
G01D02*
Y1235802D01*
G01D02*
X76155Y1235502D01*
G01D02*
X76193Y1234968D01*
G01D02*
X76184Y1234959D01*
G01D02*
G02X76199Y1234550I-5926J-422D01*
G01D02*
Y1230550D01*
G01D02*
G02X74573Y1226624I-5553J0D01*
G01D02*
X67748Y1219799D01*
G01X83700Y1248600D02*
X81727Y1250574D01*
G01D02*
G03X77800Y1252200I-3926J-3927D01*
G01D02*
X72449D01*
G01D02*
G02X71000Y1252800I0J2049D01*
G01D02*
G02X69999Y1255217I2417J2417D01*
G01D02*
Y1380358D01*
G01X82647Y1251494D02*
G03X77799Y1253500I-4845J-4848D01*
G01D02*
X72448D01*
G01D02*
G02X71920Y1253720I2J748D01*
G01D02*
G02X71300Y1255217I1497J1497D01*
G01D02*
X71299Y1255216D01*
G01D02*
Y1380359D01*
G01X67299Y1391216D02*
Y1250152D01*
G01D02*
X67300Y1250153D01*
G01D02*
G03X68998Y1246051I5802J-1D01*
G01D02*
X68999D01*
G01D02*
X76184Y1238866D01*
G01X65999Y1391217D02*
Y1250153D01*
G01D02*
G03X68079Y1245131I7102J0D01*
G01D02*
X75264Y1237946D01*
G01X83179Y1336050D02*
G02X81991Y1336542I0J1680D01*
G01D02*
G03X80803Y1337034I-1188J-1188D01*
G01D02*
X80790Y1337047D01*
G01D02*
X77166D01*
G01X82353Y1334750D02*
G03X81749Y1334500I0J-854D01*
G01D02*
G02X80264Y1333885I-1485J1485D01*
G01D02*
X80251Y1333898D01*
G01D02*
X77166D01*
G01X82582Y1344050D02*
G03X82099Y1343850I0J-683D01*
G01D02*
G02X80853Y1343334I-1246J1246D01*
G01D02*
X80840Y1343347D01*
G01D02*
X77166D01*
G01X82399Y1345550D02*
G03X80147Y1346483I-2252J-2252D01*
G01D02*
X80134Y1346496D01*
G01D02*
X77166D01*
G01X69999Y1380358D02*
G02X71681Y1384419I5742J1D01*
G01D02*
X71680D01*
G01D02*
X73180Y1385919D01*
G01X71299Y1380359D02*
G02X72600Y1383500I4442J0D01*
G01D02*
X74100Y1385000D01*
G01X73180Y1385919D02*
X73181D01*
G01D02*
G02X76757Y1387400I3575J-3575D01*
G01D02*
X83327D01*
G01X74100Y1385000D02*
G02X76756Y1386100I2656J-2656D01*
G01D02*
X83326D01*
G01X76543Y1407399D02*
Y1404999D01*
G01D02*
G02X75584Y1402683I-3276J0D01*
G01D02*
X75200Y1402299D01*
G01D02*
X75199D01*
G01D02*
X69550Y1396650D01*
G01D02*
G03X67299Y1391216I5434J-5434D01*
G01X75243Y1407400D02*
Y1405000D01*
G01D02*
G02X74664Y1403603I-1975J0D01*
G01D02*
X68630Y1397569D01*
G01D02*
G03X65999Y1391217I6354J-6353D01*
G01X81449Y1437050D02*
Y1426259D01*
G01D02*
G03X83575Y1421126I7259J0D01*
G01X85234Y1403549D02*
X75616Y1413167D01*
G01D02*
X75472Y1413312D01*
G01D02*
G03X71999Y1414750I-3472J-3473D01*
G01D02*
X67193D01*
G01D02*
G02X64359Y1415924I0J4008D01*
G01D02*
X63366Y1416917D01*
G01D02*
G02X62081Y1420019I3102J3102D01*
G01D02*
Y1446335D01*
G01X82659Y1407964D02*
X81711Y1408912D01*
G01D02*
Y1408911D01*
G01D02*
X81710Y1408910D01*
G01D02*
X76392Y1414231D01*
G01D02*
G03X71999Y1416050I-4392J-4393D01*
G01D02*
X67196D01*
G01D02*
G02X65277Y1416845I0J2714D01*
G01D02*
X64286Y1417837D01*
G01D02*
G02X63381Y1420019I2181J2183D01*
G01D02*
Y1446334D01*
G01X63844Y1413044D02*
G03X65775Y1412244I1931J1931D01*
G01D02*
X71479D01*
G01D02*
G02X74318Y1411068I0J-4015D01*
G01D02*
X75492Y1409893D01*
G01D02*
X75493Y1409894D01*
G01D02*
X75524Y1409863D01*
G01D02*
G02X76543Y1407399I-2464J-2462D01*
G01X61925Y1413123D02*
X62924Y1412124D01*
G01D02*
X62925Y1412125D01*
G01D02*
G03X65774Y1410944I2851J2850D01*
G01D02*
X71478D01*
G01D02*
G02X73399Y1410148I0J-2715D01*
G01D02*
X74604Y1408943D01*
G01D02*
G02X75243Y1407400I-1543J-1543D01*
G01X63047Y1406309D02*
G03X61498Y1410049I-5288J1D01*
G01D02*
X61499Y1410050D01*
G01D02*
X61498Y1410051D01*
G01X80453Y1442595D02*
G02X82749Y1437051I-5545J-5544D01*
G01X79532Y1441678D02*
G02X81449Y1437050I-4628J-4628D01*
G01X63381Y1446334D02*
G03X61214Y1451570I-7404J2D01*
G01X72718Y1622680D02*
G03X77279Y1624570I0J6449D01*
G01D02*
G03X78278Y1626980I-2408J2410D01*
G01D02*
Y1638551D01*
G01D02*
G03X76805Y1642103I-5024J-2D01*
G01X72719Y1621380D02*
G03X78199Y1623650I0J7750D01*
G01D02*
G03X79578Y1626979I-3329J3329D01*
G01D02*
Y1638551D01*
G01D02*
G03X77725Y1643023I-6325J-1D01*
G01X65949Y1660004D02*
G02X62834Y1652484I-10635J0D01*
G01X64649Y1659842D02*
G02X62030Y1653519I-8942J0D01*
G01X76805Y1642103D02*
X72900Y1646008D01*
G01D02*
G02X68349Y1656995I10987J10987D01*
G01D02*
Y1780791D01*
G01X77725Y1643023D02*
X73820Y1646928D01*
G01D02*
G02X73262Y1647519I10069J10066D01*
G01D02*
X73259Y1647522D01*
G01D02*
G02X69649Y1656996I10626J9474D01*
G01D02*
Y1684667D01*
G01X62249Y1660581D02*
Y1811237D01*
G01X65949Y1794933D02*
Y1660004D01*
G01X64649Y1794934D02*
Y1659842D01*
G01X69649Y1684667D02*
G02X70024Y1685042I375J0D01*
G01D02*
X70025D01*
G01D02*
G03X70400Y1685417I0J375D01*
G01D02*
Y1687067D01*
G01D02*
G03X70025Y1687442I-375J0D01*
G01D02*
X70024D01*
G01D02*
G02X69649Y1687817I0J375D01*
G01D02*
Y1689467D01*
G01D02*
G02X70024Y1689842I375J0D01*
G01D02*
X70025D01*
G01D02*
G03X70400Y1690217I0J375D01*
G01D02*
Y1691867D01*
G01D02*
G03X70025Y1692242I-375J0D01*
G01D02*
X70024D01*
G01D02*
G02X69649Y1692617I0J375D01*
G01D02*
Y1705431D01*
G01D02*
G02X70074Y1705856I425J0D01*
G01D02*
G03X70499Y1706281I0J425D01*
G01D02*
Y1707831D01*
G01D02*
G03X70074Y1708256I-425J0D01*
G01D02*
G02X69649Y1708681I0J425D01*
G01D02*
Y1710231D01*
G01D02*
G02X70074Y1710656I425J0D01*
G01D02*
G03X70499Y1711081I0J425D01*
G01D02*
Y1712631D01*
G01D02*
G03X70074Y1713056I-425J0D01*
G01D02*
G02X69649Y1713481I0J425D01*
G01D02*
Y1714094D01*
G01D02*
G02X70049Y1714494I400J0D01*
G01D02*
G03X70449Y1714894I0J400D01*
G01D02*
Y1716494D01*
G01D02*
G03X70049Y1716894I-400J0D01*
G01D02*
G02X69649Y1717294I0J400D01*
G01D02*
Y1780791D01*
G01X83361Y1741850D02*
G02X82190Y1742335I0J1656D01*
G01D02*
G03X81681Y1742546I-509J-509D01*
G01D02*
X81668Y1742559D01*
G01D02*
X77166D01*
G01X82249Y1740300D02*
X81799Y1739850D01*
G01D02*
G02X80705Y1739397I-1094J1094D01*
G01D02*
X80692Y1739410D01*
G01D02*
X77166D01*
G01X82492Y1750050D02*
G03X81558Y1749663I0J-1321D01*
G01D02*
X81293Y1749397D01*
G01D02*
G02X79963Y1748846I-1330J1330D01*
G01D02*
X79950Y1748859D01*
G01D02*
X77166D01*
G01X82498Y1751350D02*
G02X81972Y1751509I0J949D01*
G01D02*
G02X81829Y1751626I522J784D01*
G01D02*
X81701Y1751754D01*
G01D02*
G03X80737Y1751995I-963J-1804D01*
G01D02*
X80724Y1752008D01*
G01D02*
X77166D01*
G01X68349Y1780791D02*
G02X71493Y1788384I10738J1D01*
G01X69649Y1780791D02*
G02X72413Y1787464I9437J0D01*
G01X85127Y1804334D02*
G03X80499Y1806251I-4628J-4628D01*
G01D02*
Y1806250D01*
G01D02*
X75999D01*
G01D02*
G03X71219Y1804270I0J-6760D01*
G01D02*
X68825Y1801876D01*
G01D02*
G03X65949Y1794933I6943J-6943D01*
G01X86047Y1805254D02*
G03X80342Y1807550I-5547J-5548D01*
G01D02*
X75999D01*
G01D02*
G03X70299Y1805189I0J-8061D01*
G01D02*
X67905Y1802795D01*
G01D02*
G03X64649Y1794934I7863J-7862D01*
G01X71493Y1788384D02*
X75457Y1792348D01*
G01D02*
G02X81499Y1794849I6040J-6042D01*
G01D02*
Y1794850D01*
G01D02*
X87106D01*
G01X72413Y1787464D02*
X75999Y1791050D01*
G01D02*
X76377Y1791429D01*
G01D02*
G02X81499Y1793550I5121J-5122D01*
G01D02*
X87106D01*
G01X127999Y1822866D02*
X67459D01*
G01D02*
G03X64832Y1821778I0J-3715D01*
G01X127999Y1824166D02*
X67460D01*
G01D02*
G03X63913Y1822697I-1J-5015D01*
G01D02*
X63912D01*
G01X62444Y1815446D02*
X65830Y1818833D01*
G01D02*
G02X69774Y1820466I3943J-3944D01*
G01D02*
X124599D01*
G01X62249Y1811237D02*
G02X63414Y1814576I5370J-1D01*
G01D02*
X66750Y1817913D01*
G01D02*
G02X69774Y1819166I3025J-3024D01*
G01D02*
X124599D01*
G01X94783Y1860250D02*
X62475D01*
G01X94784Y1861550D02*
X62474D01*
G01X62841Y1856683D02*
X88041D01*
G01X62842Y1855383D02*
X88040D01*
G01X103499Y128550D02*
X101299D01*
G01D02*
G03X99099Y126350I0J-2200D01*
G01D02*
Y122894D01*
G01D02*
G02X95899Y119694I-3200J0D01*
G01X103774Y127250D02*
X101299D01*
G01D02*
G03X100399Y126350I0J-900D01*
G01D02*
Y122894D01*
G01D02*
G02X95899Y118394I-4500J0D01*
G01X86599Y126750D02*
X86218Y127131D01*
G01D02*
G03X84499Y127843I-1719J-1719D01*
G01X86899Y130567D02*
Y130543D01*
G01D02*
G02X85499Y129143I-1400J0D01*
G01X105249Y145050D02*
G02X102199Y144278I-3050J5639D01*
G01D02*
X91629D01*
G01D02*
G02X91229Y144678I0J400D01*
G01D02*
Y145728D01*
G01D02*
G03X90829Y146128I-400J0D01*
G01D02*
X90816Y146141D01*
G01D02*
X85630D01*
G01X105249Y141550D02*
G03X102348Y142947I-3447J-3447D01*
G01D02*
G03X102114Y142967I-532J-4845D01*
G01D02*
G03X101802Y142978I-328J-4863D01*
G01D02*
X91629D01*
G01D02*
G03X91229Y142578I0J-400D01*
G01D02*
Y141528D01*
G01D02*
G02X90829Y141128I-400J0D01*
G01D02*
X90816Y141141D01*
G01D02*
X85630D01*
G01X103420Y158731D02*
G02X101602Y157978I-1818J1818D01*
G01D02*
X91629D01*
G01D02*
G03X91229Y157578I0J-400D01*
G01D02*
Y156528D01*
G01D02*
G02X90829Y156128I-400J0D01*
G01D02*
X90816Y156141D01*
G01D02*
X85630D01*
G01X103676Y158988D02*
X103420Y158731D01*
G01X104099Y163150D02*
G02X102755Y159907I-4587J1D01*
G01D02*
X102499Y159650D01*
G01D02*
G02X101601Y159278I-898J898D01*
G01D02*
X91629D01*
G01D02*
G02X91229Y159678I0J400D01*
G01D02*
Y160728D01*
G01D02*
G03X90829Y161128I-400J0D01*
G01D02*
X90816Y161141D01*
G01D02*
X85630D01*
G01X102830Y221615D02*
G02X104099Y218550I-3065J-3064D01*
G01X101899Y426252D02*
Y225298D01*
G01D02*
G03X102544Y223741I2202J0D01*
G01D02*
X103749Y222536D01*
G01X100599Y395751D02*
Y225399D01*
G01D02*
G03X101697Y222748I3748J-1D01*
G01D02*
X101696Y222747D01*
G01D02*
X102612Y221832D01*
G01D02*
X102830Y221615D01*
G01X100599Y416994D02*
Y403449D01*
G01D02*
G02X100350Y403200I-249J0D01*
G01D02*
X100349D01*
G01D02*
G03X100100Y402951I0J-249D01*
G01D02*
Y401049D01*
G01D02*
G03X100349Y400800I249J0D01*
G01D02*
X100350D01*
G01D02*
G02X100599Y400551I0J-249D01*
G01D02*
Y398649D01*
G01D02*
G02X100350Y398400I-249J0D01*
G01D02*
X100349D01*
G01D02*
G03X100100Y398151I0J-249D01*
G01D02*
Y396249D01*
G01D02*
G03X100349Y396000I249J0D01*
G01D02*
X100350D01*
G01D02*
G02X100599Y395751I0J-249D01*
G01X103644Y429404D02*
X102894Y428654D01*
G01D02*
G03X101899Y426252I2402J-2402D01*
G01X104099Y433550D02*
G02X102790Y430389I-4471J0D01*
G01D02*
X101974Y429573D01*
G01D02*
X101975D01*
G01D02*
G03X100599Y426253I3321J-3322D01*
G01D02*
Y424794D01*
G01D02*
G02X100299Y424494I-300J0D01*
G01D02*
G03X99999Y424194I0J-300D01*
G01D02*
Y422394D01*
G01D02*
G03X100299Y422094I300J0D01*
G01D02*
G02X100599Y421794I0J-300D01*
G01D02*
Y419994D01*
G01D02*
G02X100299Y419694I-300J0D01*
G01D02*
G03X99999Y419394I0J-300D01*
G01D02*
Y417594D01*
G01D02*
G03X100299Y417294I300J0D01*
G01D02*
G02X100599Y416994I0J-300D01*
G01X101161Y517650D02*
G03X98819Y516680I0J-3312D01*
G01D02*
X98418Y516279D01*
G01D02*
G03X97901Y515027I1255J-1251D01*
G01D02*
X97900Y515028D01*
G01D02*
G03X98344Y513956I1516J0D01*
G01D02*
X98900Y513400D01*
G01X95500D02*
X96227Y514126D01*
G01D02*
G03X96600Y515028I-902J901D01*
G01D02*
G02X97500Y517200I3073J-1D01*
G01D02*
X97899Y517599D01*
G01D02*
G02X101161Y518950I3261J-3261D01*
G01X109018Y517650D02*
X101161D01*
G01Y518950D02*
X109017D01*
G01X101195Y525988D02*
G02X99655Y525350I-1540J1540D01*
G01X101195Y522488D02*
G03X97424Y524050I-3771J-3771D01*
G01D02*
X83789D01*
G01D02*
G03X83475Y524029I2J-2390D01*
G01X86199Y532250D02*
G03X84026Y533150I-2173J-2173D01*
G01D02*
X82703D01*
G01X86199Y536025D02*
X84986Y534812D01*
G01D02*
G02X84111Y534450I-874J875D01*
G01D02*
X82809D01*
G01X85630Y551653D02*
X90816D01*
G01D02*
X90829Y551640D01*
G01D02*
G02X91229Y551240I0J-400D01*
G01D02*
Y550190D01*
G01D02*
G03X91629Y549790I400J0D01*
G01D02*
X102303D01*
G01D02*
G03X105195Y550988I0J4090D01*
G01X85630Y546653D02*
X90816D01*
G01D02*
X90829Y546640D01*
G01D02*
G03X91229Y547040I0J400D01*
G01D02*
Y548090D01*
G01D02*
G02X91629Y548490I400J0D01*
G01D02*
X102776D01*
G01D02*
G02X105195Y547488I0J-3421D01*
G01X100799Y611550D02*
Y569661D01*
G01D02*
G02X98599Y564350I-7511J0D01*
G01D02*
G02X96523Y563490I-2076J2076D01*
G01D02*
X91629D01*
G01D02*
G03X91229Y563090I0J-400D01*
G01D02*
Y562040D01*
G01D02*
G02X90829Y561640I-400J0D01*
G01D02*
X90816Y561653D01*
G01D02*
X85630D01*
G01X99499Y611551D02*
Y569662D01*
G01D02*
G02X97679Y565270I-6210J0D01*
G01D02*
G02X96522Y564790I-1157J1155D01*
G01D02*
X91629D01*
G01D02*
G02X91229Y565190I0J400D01*
G01D02*
Y566240D01*
G01D02*
G03X90829Y566640I-400J0D01*
G01D02*
X90816Y566653D01*
G01D02*
X85630D01*
G01X84229Y580619D02*
G03X85299Y583202I-2583J2583D01*
G01X85149Y579700D02*
G03X86599Y583201I-3503J3502D01*
G01X85299Y583202D02*
Y651336D01*
G01X86599Y583201D02*
Y651337D01*
G01X114738Y604811D02*
X96498Y623050D01*
G01D02*
X96499Y623051D01*
G01D02*
G02X95199Y626190I3138J3138D01*
G01X115238Y606149D02*
X97418Y623970D01*
G01X92799Y624050D02*
G03X94539Y619849I5941J0D01*
G01D02*
X99358Y615029D01*
G01D02*
G02X100799Y611550I-3479J-3479D01*
G01X91499Y624051D02*
G03X93619Y618929I7242J-2D01*
G01D02*
X98122Y614427D01*
G01D02*
X98121Y614426D01*
G01D02*
X98438Y614109D01*
G01D02*
G02X99499Y611551I-2558J-2560D01*
G01X100498Y625049D02*
X118916Y606633D01*
G01X95199Y626190D02*
Y728051D01*
G01X97418Y623970D02*
G02X96499Y626189I2219J2219D01*
G01D02*
Y728052D01*
G01X92799Y729550D02*
Y624050D01*
G01X91499Y729549D02*
Y624051D01*
G01X103999Y627051D02*
G02X102599Y630429I3379J3379D01*
G01D02*
Y723051D01*
G01X100199Y725550D02*
Y628559D01*
G01D02*
G03X101168Y626220I3308J0D01*
G01D02*
X119858Y607529D01*
G01X98899Y725549D02*
Y628558D01*
G01D02*
G03X100249Y625301I4608J2D01*
G01D02*
X100248Y625300D01*
G01D02*
X100498Y625049D01*
G01X85299Y651336D02*
G03X84299Y653750I-3414J0D01*
G01X86599Y651337D02*
G03X85219Y654669I-4714J-1D01*
G01X95199Y728051D02*
G02X97347Y733238I7337J0D01*
G01X96499Y728052D02*
G02X98267Y732318I6036J-2D01*
G01X102599Y723051D02*
G02X105385Y729775I9511J-2D01*
G01X102461Y731012D02*
G03X100200Y725549I5464J-5461D01*
G01D02*
X100199Y725550D01*
G01X101541Y731932D02*
G03X98899Y725549I6384J-6380D01*
G01X97347Y733238D02*
X99079Y734970D01*
G01D02*
X119093Y754983D01*
G01X98267Y732318D02*
X99999Y734050D01*
G01D02*
X120013Y754063D01*
G01X117346Y757057D02*
X94892Y734603D01*
G01D02*
G03X92800Y729549I5054J-5052D01*
G01D02*
X92799Y729550D01*
G01X116426Y757977D02*
X93972Y735523D01*
G01D02*
G03X91499Y729549I5974J-5972D01*
G01X124914Y753465D02*
X102461Y731012D01*
G01X123994Y754385D02*
X101541Y731932D01*
G01X103295Y931489D02*
X103685Y931099D01*
G01X103295Y927989D02*
X103331Y928026D01*
G01D02*
G02X105532Y929070I2567J-2569D01*
G01X99795Y931489D02*
X98278D01*
G01D02*
G03X96950Y930939I0J-1878D01*
G01D02*
G02X95622Y930389I-1328J1328D01*
G01D02*
X83421D01*
G01X82328Y928765D02*
G02X83422Y929089I1095J-1687D01*
G01D02*
X96133D01*
G01D02*
G02X97461Y928539I0J-1878D01*
G01D02*
G03X98789Y927989I1328J1328D01*
G01D02*
X99795D01*
G01X86399Y937050D02*
G03X85975Y938074I-1449J0D01*
G01D02*
X85799Y938250D01*
G01D02*
G03X84592Y938750I-1207J-1207D01*
G01D02*
X82994D01*
G01X85999Y940429D02*
G02X85246Y940117I-753J753D01*
G01D02*
X82839D01*
G01X104795Y956489D02*
G02X101929Y955302I-2866J2866D01*
G01D02*
X91629D01*
G01D02*
G02X91229Y955702I0J400D01*
G01D02*
Y956752D01*
G01D02*
G03X90829Y957152I-400J0D01*
G01D02*
X90816Y957165D01*
G01D02*
X85630D01*
G01X104795Y952989D02*
G03X102349Y954002I-2446J-2446D01*
G01D02*
X91629D01*
G01D02*
G03X91229Y953602I0J-400D01*
G01D02*
Y952552D01*
G01D02*
G02X90829Y952152I-400J0D01*
G01D02*
X90816Y952165D01*
G01D02*
X85630D01*
G01X97799Y1002550D02*
Y973030D01*
G01D02*
G02X96399Y969650I-4780J0D01*
G01D02*
G02X94835Y969002I-1564J1564D01*
G01D02*
X91629D01*
G01D02*
G03X91229Y968602I0J-400D01*
G01D02*
Y967552D01*
G01D02*
G02X90829Y967152I-400J0D01*
G01D02*
X90816Y967165D01*
G01D02*
X85630D01*
G01X96499Y1002550D02*
Y973029D01*
G01D02*
G02X95479Y970570I-3479J2D01*
G01D02*
G02X94834Y970302I-646J643D01*
G01D02*
X91629D01*
G01D02*
G02X91229Y970702I0J400D01*
G01D02*
Y971752D01*
G01D02*
G03X90829Y972152I-400J0D01*
G01D02*
X90816Y972165D01*
G01D02*
X85630D01*
G01X111762Y995446D02*
X97079Y1010130D01*
G01X95651Y1007738D02*
G02X97799Y1002550I-5188J-5187D01*
G01X94731Y1006818D02*
G02X96499Y1002550I-4268J-4268D01*
G01X112682Y996366D02*
X97999Y1011050D01*
G01X85900Y1236522D02*
Y1243289D01*
G01X87200Y1236519D02*
Y1243290D01*
G01X85900Y1243289D02*
G03X83700Y1248600I-7511J0D01*
G01X87200Y1243290D02*
G03X86284Y1247202I-8811J0D01*
G01D02*
G03X84620Y1249520I-7895J-3911D01*
G01D02*
X82647Y1251494D01*
G01X100578Y1336952D02*
G02X98400Y1336050I-2178J2178D01*
G01D02*
X83179D01*
G01X100578Y1333452D02*
X100115Y1333915D01*
G01D02*
G03X98099Y1334750I-2016J-2016D01*
G01D02*
X82353D01*
G01X103509Y1361383D02*
G02X102135Y1360814I-1374J1374D01*
G01D02*
X92424D01*
G01D02*
G02X91499Y1361739I0J925D01*
G01D02*
G03X90574Y1362664I-925J0D01*
G01D02*
X90561Y1362677D01*
G01D02*
X85630D01*
G01X103547Y1358983D02*
G03X102265Y1359514I-1282J-1282D01*
G01D02*
X92424D01*
G01D02*
G03X91499Y1358589I0J-925D01*
G01D02*
G02X90574Y1357664I-925J0D01*
G01D02*
X90561Y1357677D01*
G01D02*
X85630D01*
G01X86890Y1342860D02*
G03X84017Y1344050I-2873J-2873D01*
G01D02*
X82582D01*
G01X86890Y1346635D02*
X86882Y1346627D01*
G01D02*
G02X83799Y1345350I-3083J3083D01*
G01D02*
X82882D01*
G01D02*
G02X82399Y1345550I0J683D01*
G01X102350Y1348154D02*
Y1348150D01*
G01D02*
G03X103500Y1347000I1150J0D01*
G01X102350Y1344500D02*
X102891Y1345040D01*
G01D02*
G02X104000Y1345500I1110J-1109D01*
G01X97229Y1373337D02*
X96813Y1373753D01*
G01D02*
G03X94975Y1374514I-1838J-1839D01*
G01D02*
X91629D01*
G01D02*
G03X91229Y1374114I0J-400D01*
G01D02*
Y1373064D01*
G01D02*
G02X90829Y1372664I-400J0D01*
G01D02*
X90816Y1372677D01*
G01D02*
X85630D01*
G01X97000Y1377600D02*
X96496Y1377097D01*
G01D02*
G02X93400Y1375814I-3097J3096D01*
G01D02*
X91629D01*
G01D02*
G02X91229Y1376214I0J400D01*
G01D02*
Y1377264D01*
G01D02*
G03X90829Y1377664I-400J0D01*
G01D02*
X90816Y1377677D01*
G01D02*
X85630D01*
G01X95826Y1410713D02*
X211991Y1294542D01*
G01X94906Y1409793D02*
X206324Y1298375D01*
G01X83327Y1387400D02*
G03X85500Y1388300I0J3073D01*
G01D02*
X86600Y1389400D01*
G01D02*
G03X87491Y1391551I-2151J2151D01*
G01D02*
Y1398100D01*
G01D02*
G03X85234Y1403549I-7706J0D01*
G01X83326Y1386100D02*
G03X86419Y1387381I1J4373D01*
G01D02*
Y1387380D01*
G01D02*
X87519Y1388480D01*
G01D02*
Y1388481D01*
G01D02*
G03X88791Y1391550I-3070J3070D01*
G01D02*
Y1398100D01*
G01D02*
G03X86153Y1404467I-9005J-1D01*
G01D02*
X85719Y1404902D01*
G01D02*
X82659Y1407964D01*
G01X99904Y1427955D02*
X100976Y1426883D01*
G01D02*
X100977Y1426881D01*
G01D02*
X102854Y1425004D01*
G01D02*
X105904Y1421955D01*
G01X96749Y1432436D02*
G03X98984Y1427035I7643J0D01*
G01D02*
X100054Y1425965D01*
G01D02*
X100055Y1425963D01*
G01D02*
X101934Y1424084D01*
G01D02*
X104984Y1421035D01*
G01X250866Y1269918D02*
X95616Y1425168D01*
G01D02*
X95040Y1425745D01*
G01D02*
G02X93049Y1430550I4805J4806D01*
G01X251835Y1270788D02*
X96536Y1426087D01*
G01D02*
X95960Y1426664D01*
G01D02*
Y1426665D01*
G01D02*
G02X95173Y1427658I3884J3887D01*
G01X90650Y1429948D02*
G03X92918Y1424470I7748J-1D01*
G01D02*
X240321Y1277068D01*
G01X89349Y1429946D02*
G03X91998Y1423549I9046J-1D01*
G01D02*
X92303Y1423246D01*
G01D02*
X239352Y1276197D01*
G01X214569Y1295366D02*
X87191Y1422744D01*
G01D02*
G02X85149Y1427674I4932J4931D01*
G01X215490Y1296284D02*
X88111Y1423663D01*
G01D02*
G02X86449Y1427675I4012J4012D01*
G01X82749Y1437051D02*
Y1426259D01*
G01D02*
G03X84494Y1422046I5958J0D01*
G01D02*
X95826Y1410714D01*
G01D02*
Y1410713D01*
G01X83575Y1421126D02*
X94526Y1410175D01*
G01D02*
X94525Y1410174D01*
G01D02*
X94906Y1409794D01*
G01D02*
Y1409793D01*
G01X107602Y1423653D02*
X103012Y1428241D01*
G01D02*
G02X100449Y1434429I6190J6189D01*
G01D02*
Y1458970D01*
G01X103932Y1429160D02*
G02X101749Y1434430I5270J5270D01*
G01D02*
Y1458971D01*
G01X98049Y1455825D02*
Y1432435D01*
G01D02*
G03X99904Y1427955I6337J0D01*
G01X96749Y1455825D02*
Y1432436D01*
G01X93049Y1430550D02*
Y1452050D01*
G01X95173Y1427658D02*
G02X94349Y1430550I4672J2894D01*
G01D02*
Y1452051D01*
G01X90649Y1450050D02*
Y1429947D01*
G01D02*
X90650Y1429948D01*
G01X89349Y1450049D02*
Y1429948D01*
G01D02*
G03Y1429946I9048J-1D01*
G01X85149Y1427674D02*
Y1438550D01*
G01D02*
G03X83208Y1443236I-6627J0D01*
G01X86449Y1427675D02*
Y1438549D01*
G01D02*
G03X84128Y1444156I-7928J2D01*
G01D02*
X83866Y1444418D01*
G01D02*
X83865Y1444417D01*
G01X100449Y1458970D02*
G03X98829Y1462881I-5531J0D01*
G01X101749Y1458971D02*
G03X99749Y1463800I-6831J-1D01*
G01X95918Y1460970D02*
G02X98049Y1455825I-5144J-5144D01*
G01X94999Y1460050D02*
G02X96749Y1455825I-4225J-4225D01*
G01X93049Y1452050D02*
G03X91505Y1455778I-5273J0D01*
G01X94349Y1452051D02*
G03X92425Y1456698I-6574J0D01*
G01D02*
X92286Y1456837D01*
G01D02*
X92285Y1456836D01*
G01X88394Y1455494D02*
G02X90649Y1450050I-5444J-5444D01*
G01X87474Y1454574D02*
G02X89349Y1450049I-4523J-4525D01*
G01X101749Y1743050D02*
X101503Y1742805D01*
G01D02*
G02X99199Y1741850I-2305J2304D01*
G01D02*
X83361D01*
G01X101749Y1739550D02*
G03X99335Y1740550I-2414J-2414D01*
G01D02*
X82853D01*
G01D02*
G03X82249Y1740300I0J-854D01*
G01X103749Y1764050D02*
G03X101393Y1765026I-2356J-2356D01*
G01D02*
X91629D01*
G01D02*
G03X91563Y1765020I3J-400D01*
G01D02*
G03X91229Y1764626I65J-394D01*
G01D02*
Y1763576D01*
G01D02*
G02X90829Y1763176I-400J0D01*
G01D02*
X90816Y1763189D01*
G01D02*
X85630D01*
G01X85194Y1748848D02*
G03X85199I3J102D01*
G01D02*
Y1748950D01*
G01D02*
G03X85084Y1749227I-391J0D01*
G01D02*
X84800Y1749511D01*
G01D02*
G03X83499Y1750050I-1301J-1301D01*
G01D02*
X82492D01*
G01X85341Y1752245D02*
G02X83744Y1751402I-2161J2161D01*
G01D02*
G02X83180Y1751350I-561J3004D01*
G01D02*
X82498D01*
G01X111867Y1777594D02*
X85127Y1804334D01*
G01X103749Y1767550D02*
G02X100794Y1766326I-2955J2955D01*
G01D02*
X91629D01*
G01D02*
G02X91229Y1766726I0J400D01*
G01D02*
Y1767050D01*
G01D02*
G03X90946Y1767733I-966J0D01*
G01D02*
X90814Y1767865D01*
G01D02*
G03X90063Y1768176I-751J-751D01*
G01D02*
X90050Y1768189D01*
G01D02*
X85630D01*
G01X96921Y1787965D02*
G02X97799Y1785845I-2120J-2120D01*
G01D02*
Y1782800D01*
G01D02*
G02X96514Y1780585I-2550J-1D01*
G01D02*
Y1780586D01*
G01D02*
G02X95231Y1780250I-1265J2214D01*
G01D02*
X92536D01*
G01D02*
G03X91499Y1779213I0J-1037D01*
G01D02*
G02X90462Y1778176I-1037J0D01*
G01D02*
X90449Y1778189D01*
G01D02*
X85630D01*
G01X96001Y1787045D02*
G02X96498Y1785845I-1200J-1200D01*
G01D02*
X96499Y1785846D01*
G01D02*
Y1782799D01*
G01D02*
X96498Y1782800D01*
G01D02*
G02X95909Y1781738I-1250J-1D01*
G01D02*
X95869Y1781715D01*
G01D02*
G02X95240Y1781550I-621J1085D01*
G01D02*
X93248D01*
G01D02*
G02X92823Y1781726I0J601D01*
G01D02*
X91799Y1782750D01*
G01D02*
G03X90771Y1783176I-1028J-1028D01*
G01D02*
X90758Y1783189D01*
G01D02*
X85630D01*
G01X112787Y1778514D02*
X86047Y1805254D01*
G01X87106Y1794850D02*
G02X92111Y1792777I1J-7076D01*
G01D02*
X96418Y1788469D01*
G01D02*
X96921Y1787965D01*
G01X87106Y1793550D02*
G02X90507Y1792442I-1J-5778D01*
G01D02*
G02X91191Y1791857I-3403J-4671D01*
G01D02*
X95498Y1787550D01*
G01D02*
X96001Y1787046D01*
G01D02*
Y1787045D01*
G01X95547Y1853574D02*
X112535Y1836586D01*
G01X94628Y1852654D02*
X111615Y1835666D01*
G01X108069Y1849620D02*
X99319Y1858371D01*
G01D02*
G03X94783Y1860250I-4536J-4536D01*
G01X108989Y1850540D02*
X100238Y1859291D01*
G01D02*
G03X94784Y1861550I-5455J-5456D01*
G01X88041Y1856683D02*
G02X95547Y1853574I-1J-10617D01*
G01X88040Y1855383D02*
G02X94628Y1852654I0J-9317D01*
G01X108749Y129550D02*
X109999D01*
G01D02*
G02X110994Y129138I0J-1407D01*
G01D02*
X111385Y128747D01*
G01D02*
G03X111544Y128618I715J719D01*
G01D02*
G03X111950Y128450I406J406D01*
G01D02*
X114999D01*
G01D02*
G03X115876Y129327I0J877D01*
G01D02*
Y130050D01*
G01X108749Y126050D02*
X109999D01*
G01D02*
G03X110994Y126462I0J1407D01*
G01D02*
X111458Y126926D01*
G01D02*
G02X111999Y127150I541J-541D01*
G01D02*
X114499D01*
G01D02*
G02X115876Y125973I0J-1394D01*
G01X105249Y129550D02*
X104780Y129080D01*
G01D02*
G02X103499Y128550I-1280J1281D01*
G01X105249Y126050D02*
X104243Y127056D01*
G01D02*
G03X103774Y127250I-469J-470D01*
G01X108749Y145050D02*
X109778Y144021D01*
G01D02*
G03X111499Y143308I1721J1721D01*
G01D02*
X112499D01*
G01D02*
G03X113352Y143662I-1J1207D01*
G01D02*
X113620Y143929D01*
G01D02*
G03X113999Y144844I-915J915D01*
G01D02*
Y148375D01*
G01D02*
G03X113170Y150378I-2831J1D01*
G01D02*
X109395Y154153D01*
G01D02*
X109396Y154154D01*
G01D02*
G02X107799Y158010I3855J3855D01*
G01D02*
Y220383D01*
G01X108749Y141550D02*
G02X109855Y142008I1106J-1106D01*
G01D02*
X112499D01*
G01D02*
Y142009D01*
G01D02*
G03X114271Y142741I2J2507D01*
G01D02*
X114539Y143009D01*
G01D02*
Y143010D01*
G01D02*
G03X115299Y144845I-1834J1834D01*
G01D02*
Y148376D01*
G01D02*
G03X114089Y151297I-4131J0D01*
G01D02*
X110315Y155073D01*
G01D02*
G02X109099Y158009I2936J2936D01*
G01D02*
Y220382D01*
G01X105399Y218550D02*
Y163150D01*
G01D02*
X105398D01*
G01D02*
G02X103676Y158988I-5887J-2D01*
G01X104099Y208713D02*
Y163150D01*
G01X107799Y220383D02*
X107798Y220382D01*
G01D02*
G03X107298Y222219I-3618J2D01*
G01X109099Y220382D02*
G03X107659Y223860I-4918J1D01*
G01X103749Y222536D02*
G02X105399Y218550I-3985J-3984D01*
G01X104099D02*
Y216511D01*
G01D02*
G02X103800Y216212I-299J0D01*
G01D02*
X103799D01*
G01D02*
G03X103500Y215913I0J-299D01*
G01D02*
Y214111D01*
G01D02*
G03X103799Y213812I299J0D01*
G01D02*
X103800D01*
G01D02*
G02X104099Y213513I0J-299D01*
G01D02*
Y211711D01*
G01D02*
G02X103800Y211412I-299J0D01*
G01D02*
X103799D01*
G01D02*
G03X103500Y211113I0J-299D01*
G01D02*
Y209311D01*
G01D02*
G03X103799Y209012I299J0D01*
G01D02*
X103800D01*
G01D02*
G02X104099Y208713I0J-299D01*
G01X117538Y225012D02*
X127983Y214567D01*
G01X116691Y224019D02*
X127063Y213647D01*
G01X107298Y222219D02*
X107297D01*
G01D02*
G03X106740Y222940I-3118J-1833D01*
G01D02*
X106420Y223259D01*
G01D02*
X105564Y224115D01*
G01D02*
G02X104299Y227167I3053J3054D01*
G01D02*
Y424834D01*
G01X107659Y223860D02*
X107339Y224179D01*
G01D02*
X106482Y225036D01*
G01D02*
G02X105599Y227168I2132J2132D01*
G01D02*
Y424835D01*
G01X124999Y225375D02*
X122451D01*
G01D02*
G02X119820Y226389I-173J3472D01*
G01D02*
X118635Y227574D01*
G01D02*
G02X117699Y230050I2275J2275D01*
G01D02*
Y479051D01*
G01X124701Y226675D02*
X122418D01*
G01D02*
X122387Y226674D01*
G01D02*
G02X120739Y227308I-110J2174D01*
G01D02*
X120740Y227309D01*
G01D02*
X119555Y228494D01*
G01D02*
X119554Y228493D01*
G01D02*
G02X118997Y229969I1356J1355D01*
G01D02*
G03X118999Y230050I-1051J66D01*
G01D02*
Y479050D01*
G01X115200Y480550D02*
Y229050D01*
G01D02*
G03X117499Y225050I4629J0D01*
G01D02*
X117520Y225029D01*
G01D02*
G02X117538Y225012I-265J-299D01*
G01X113900Y480549D02*
Y229050D01*
G01D02*
G03X116691Y224019I5930J0D01*
G01X127042Y249550D02*
X123765D01*
G01D02*
G03X122799Y249150I0J-1366D01*
G01X126089Y250850D02*
X123823D01*
G01D02*
G02X123099Y251150I0J1024D01*
G01D02*
X122798Y251451D01*
G01D02*
G02X122397Y252419I968J968D01*
G01D02*
Y252688D01*
G01X104299Y424834D02*
G02X105592Y427956I4414J1D01*
G01D02*
X105591D01*
G01D02*
X106466Y428831D01*
G01D02*
G03X107799Y432050I-3220J3219D01*
G01D02*
Y480770D01*
G01X105599Y424835D02*
G02X106511Y427037I3114J0D01*
G01D02*
X107011Y427537D01*
G01D02*
X107012D01*
G01D02*
X107386Y427911D01*
G01D02*
G03X109099Y432051I-4141J4138D01*
G01D02*
Y480771D01*
G01X105399Y433551D02*
G02X103710Y429469I-5772J-2D01*
G01D02*
X103645Y429404D01*
G01D02*
X103644D01*
G01X105399Y482722D02*
Y433551D01*
G01X104099Y482721D02*
Y433550D01*
G01X107799Y480770D02*
G02X109154Y484045I4630J2D01*
G01D02*
X115998Y490888D01*
G01D02*
X120579Y495469D01*
G01D02*
X121077Y495968D01*
G01D02*
Y495969D01*
G01D02*
G03X123699Y502296I-6325J6328D01*
G01X109099Y480771D02*
G02X110074Y483125I3329J0D01*
G01D02*
X121499Y494550D01*
G01D02*
X121997Y495049D01*
G01D02*
G03X124999Y502295I-7246J7247D01*
G01X118797Y498008D02*
X106734Y485945D01*
G01D02*
G03X105399Y482722I3223J-3223D01*
G01X117877Y498928D02*
X105814Y486865D01*
G01D02*
G03X104099Y482721I4144J-4142D01*
G01X117699Y479051D02*
G02X119253Y482804I5309J0D01*
G01D02*
X129999Y493550D01*
G01X118999Y479050D02*
G02X120173Y481884I4008J0D01*
G01D02*
X130919Y492630D01*
G01X127590Y495302D02*
X116870Y484582D01*
G01D02*
G03X115200Y480550I4032J-4032D01*
G01X126670Y496222D02*
X115950Y485502D01*
G01D02*
G03X113900Y480549I4953J-4951D01*
G01X123699Y502296D02*
Y606006D01*
G01X121299Y604050D02*
Y504049D01*
G01D02*
G02X118797Y498008I-8544J0D01*
G01X119999Y604051D02*
Y504048D01*
G01D02*
X119998Y504049D01*
G01D02*
G02X117877Y498928I-7243J0D01*
G01X104695Y525988D02*
G03X107351Y524888I2656J2656D01*
G01D02*
X108399D01*
G01D02*
G02X110108Y524180I0J-2417D01*
G01D02*
X110368Y523919D01*
G01D02*
X110649Y523637D01*
G01D02*
X110650D01*
G01D02*
G02X111499Y521587I-2049J-2049D01*
G01D02*
Y520417D01*
G01D02*
G02X110718Y518531I-2666J-1D01*
G01D02*
Y518530D01*
G01D02*
X110418Y518230D01*
G01D02*
G02X109018Y517650I-1400J1400D01*
G01X109017Y518950D02*
G03X109499Y519149I1J680D01*
G01D02*
X109498D01*
G01D02*
X109799Y519450D01*
G01D02*
G03X110199Y520416I-966J966D01*
G01D02*
Y521588D01*
G01D02*
G03X109731Y522718I-1598J0D01*
G01D02*
X109188Y523260D01*
G01D02*
X109189Y523261D01*
G01D02*
G03X108398Y523588I-790J-790D01*
G01D02*
X107351D01*
G01D02*
G03X104695Y522488I0J-3756D01*
G01X108695Y550988D02*
G03X111290Y549913I2595J2595D01*
G01D02*
X112499D01*
G01D02*
G03X114839Y550882I0J3310D01*
G01D02*
X115003Y551046D01*
G01D02*
G03X116199Y553933I-2887J2887D01*
G01D02*
Y574677D01*
G01X108695Y547488D02*
G02X111411Y548613I2716J-2716D01*
G01D02*
X112499D01*
G01D02*
G03X115741Y549956I0J4585D01*
G01D02*
X116111Y550326D01*
G01D02*
G03X117499Y553932I-3995J3608D01*
G01D02*
Y601282D01*
G01X116199Y574677D02*
G03X115949Y574927I-250J0D01*
G01D02*
G02X115699Y575177I0J250D01*
G01D02*
Y577077D01*
G01D02*
G02X115949Y577327I250J0D01*
G01D02*
G03X116199Y577577I0J250D01*
G01D02*
Y581573D01*
G01D02*
G03X115849Y581923I-350J0D01*
G01D02*
G02X115499Y582273I0J350D01*
G01D02*
Y583973D01*
G01D02*
G02X115849Y584323I350J0D01*
G01D02*
G03X116199Y584673I0J350D01*
G01D02*
Y586373D01*
G01D02*
G03X115849Y586723I-350J0D01*
G01D02*
G02X115499Y587073I0J350D01*
G01D02*
Y588773D01*
G01D02*
G02X115849Y589123I350J0D01*
G01D02*
G03X116199Y589473I0J350D01*
G01D02*
Y591173D01*
G01D02*
G03X115849Y591523I-350J0D01*
G01D02*
G02X115499Y591873I0J350D01*
G01D02*
Y593573D01*
G01D02*
G02X115849Y593923I350J0D01*
G01D02*
G03X116199Y594273I0J350D01*
G01D02*
Y595973D01*
G01D02*
G03X115849Y596323I-350J0D01*
G01D02*
G02X115499Y596673I0J350D01*
G01D02*
Y598373D01*
G01D02*
G02X115849Y598723I350J0D01*
G01D02*
G03X116199Y599073I0J350D01*
G01D02*
Y601283D01*
G01D02*
G03X114738Y604811I-4990J0D01*
G01X117499Y601282D02*
G03X115658Y605731I-6291J2D01*
G01D02*
X115239Y606150D01*
G01D02*
X115238Y606149D01*
G01X123699Y606006D02*
G03X122749Y608301I-3244J1D01*
G01D02*
X122748Y608300D01*
G01D02*
X103998Y627050D01*
G01X124999Y606007D02*
G03X123668Y609220I-4544J0D01*
G01D02*
X104918Y627970D01*
G01X119858Y607529D02*
G02X121299Y604050I-3479J-3479D01*
G01X118916Y606633D02*
X118915Y606632D01*
G01D02*
X118938Y606609D01*
G01D02*
G02X119999Y604051I-2558J-2560D01*
G01X115248Y632300D02*
X129248Y618300D01*
G01X130182Y611600D02*
X112363Y629419D01*
G01X131102Y612520D02*
X113283Y630339D01*
G01X108669Y629718D02*
X126918Y611469D01*
G01X108279Y628269D02*
X125998Y610549D01*
G01X103998Y627050D02*
X103999Y627051D01*
G01X104918Y627970D02*
G02X103899Y630430I2460J2460D01*
G01D02*
Y723050D01*
G01X125499Y638950D02*
X124615Y638066D01*
G01D02*
G02X123522Y637432I-1739J1740D01*
G01D02*
G02X122699Y637650I-223J819D01*
G01D02*
X122599Y637750D01*
G01D02*
G02X122399Y638233I483J483D01*
G01D02*
Y713550D01*
G01X121099Y713551D02*
Y638233D01*
G01D02*
G03X121679Y636830I1983J-1D01*
G01D02*
X121780Y636730D01*
G01D02*
G03X123865Y636178I1518J1521D01*
G01D02*
X124368D01*
G01D02*
G02X125227Y635822I0J-1214D01*
G01X129093Y631140D02*
X123785D01*
G01D02*
G02X120465Y632516I2J4697D01*
G01D02*
Y632515D01*
G01D02*
X120464Y632514D01*
G01D02*
X118714Y634264D01*
G01D02*
X118715Y634265D01*
G01D02*
Y634266D01*
G01D02*
G02X117399Y637441I3176J3177D01*
G01D02*
Y717049D01*
G01X128999Y632440D02*
X123786D01*
G01D02*
G02X121384Y633435I0J3397D01*
G01D02*
X119634Y635185D01*
G01D02*
G02X118699Y637442I2257J2257D01*
G01D02*
Y717050D01*
G01X114999Y718552D02*
Y636042D01*
G01D02*
G03X116168Y633220I3991J0D01*
G01D02*
X122544Y626844D01*
G01D02*
Y626843D01*
G01D02*
X126143Y623244D01*
G01X113699Y718551D02*
Y636041D01*
G01D02*
G03X115249Y632301I5291J2D01*
G01D02*
X115248Y632300D01*
G01X112363Y629419D02*
X112364Y629420D01*
G01D02*
G02X109999Y635130I5709J5709D01*
G01D02*
Y720051D01*
G01X113283Y630339D02*
G02X111299Y635129I4790J4790D01*
G01D02*
Y720052D01*
G01X107599Y721550D02*
Y632301D01*
G01D02*
G03X108669Y629718I3653J0D01*
G01X106299Y721549D02*
Y632300D01*
G01D02*
G03X107749Y628798I4954J0D01*
G01D02*
X108279Y628268D01*
G01D02*
Y628269D01*
G01X103899Y723050D02*
G02X106305Y728855I8210J-2D01*
G01D02*
X107224Y729774D01*
G01X122399Y713550D02*
G02X122475Y714504I6036J-1D01*
G01D02*
G02X124167Y717818I5960J-954D01*
G01D02*
X145698Y739349D01*
G01X145159Y740649D02*
X123247Y718738D01*
G01D02*
G03X121191Y714710I5188J-5187D01*
G01D02*
G03X121099Y713551I7244J-1158D01*
G01X117399Y717049D02*
G02X119334Y721726I6612J3D01*
G01D02*
X125579Y727970D01*
G01X118699Y717050D02*
G02X120254Y720806I5311J1D01*
G01D02*
X126499Y727050D01*
G01X139603Y745654D02*
X116767Y722818D01*
G01D02*
G03X114999Y718552I4268J-4268D01*
G01X138683Y746574D02*
X115847Y723738D01*
G01D02*
G03X113699Y718551I5189J-5187D01*
G01X109999Y720051D02*
G02X112359Y725750I8060J0D01*
G01D02*
X135872Y749263D01*
G01X111299Y720052D02*
X111300Y720051D01*
G01D02*
G02X113279Y724830I6760J0D01*
G01D02*
X136792Y748343D01*
G01X132712Y749923D02*
X109904Y727115D01*
G01D02*
G03X107600Y721549I5566J-5564D01*
G01D02*
X107599Y721550D01*
G01X131792Y750843D02*
X108984Y728035D01*
G01D02*
G03X106299Y721549I6486J-6484D01*
G01X105385Y729775D02*
X105384Y729776D01*
G01D02*
X106443Y730834D01*
G01D02*
G02X106444Y730835I9285J-9284D01*
G01D02*
X107579Y731970D01*
G01D02*
X127128Y751520D01*
G01X107224Y729774D02*
Y729776D01*
G01D02*
X108499Y731050D01*
G01D02*
X128048Y750600D01*
G01X119093Y754983D02*
G03X121398Y760549I-5567J5566D01*
G01D02*
X121399Y760548D01*
G01D02*
Y994946D01*
G01X120013Y754063D02*
G03X122699Y760549I-6486J6485D01*
G01D02*
Y994947D01*
G01X118999Y992550D02*
Y761049D01*
G01D02*
G02X117346Y757057I-5647J0D01*
G01X117699Y881286D02*
Y761048D01*
G01D02*
X117698Y761049D01*
G01D02*
G02X116426Y757977I-4346J0D01*
G01X125099Y757050D02*
G02X123994Y754385I-3769J1D01*
G01X117699Y912361D02*
Y889084D01*
G01D02*
G02X117400Y888785I-299J0D01*
G01D02*
X117399D01*
G01D02*
G03X117100Y888486I0J-299D01*
G01D02*
Y886684D01*
G01D02*
G03X117399Y886385I299J0D01*
G01D02*
X117400D01*
G01D02*
G02X117699Y886086I0J-299D01*
G01D02*
Y884284D01*
G01D02*
G02X117400Y883985I-299J0D01*
G01D02*
X117399D01*
G01D02*
G03X117100Y883686I0J-299D01*
G01D02*
Y881884D01*
G01D02*
G03X117399Y881585I299J0D01*
G01D02*
X117400D01*
G01D02*
G02X117699Y881286I0J-299D01*
G01X116999Y919561D02*
Y917861D01*
G01D02*
G03X117349Y917511I350J0D01*
G01D02*
G02X117699Y917161I0J-350D01*
G01D02*
Y915461D01*
G01D02*
G02X117349Y915111I-350J0D01*
G01D02*
G03X116999Y914761I0J-350D01*
G01D02*
Y913061D01*
G01D02*
G03X117349Y912711I350J0D01*
G01D02*
G02X117699Y912361I0J-350D01*
G01X103685Y931099D02*
G03X105399Y930389I1714J1714D01*
G01D02*
X108110D01*
G01D02*
G03X108499Y930550I0J550D01*
G01D02*
G03X108845Y931385I-835J835D01*
G01D02*
Y931657D01*
G01X105532Y929070D02*
G02X105899Y929089I371J-3612D01*
G01D02*
X107538D01*
G01D02*
G02X108770Y928578I-1J-1743D01*
G01D02*
X109099Y928250D01*
G01X117699Y992549D02*
Y925061D01*
G01D02*
G02X117349Y924711I-350J0D01*
G01D02*
G03X116999Y924361I0J-350D01*
G01D02*
Y922661D01*
G01D02*
G03X117349Y922311I350J0D01*
G01D02*
G02X117699Y921961I0J-350D01*
G01D02*
Y920261D01*
G01D02*
G02X117349Y919911I-350J0D01*
G01D02*
G03X116999Y919561I0J-350D01*
G01X108295Y956489D02*
G03X110951Y955389I2656J2656D01*
G01D02*
X113099D01*
G01D02*
G03X113999Y956289I0J900D01*
G01D02*
Y975102D01*
G01X108295Y952989D02*
G02X110951Y954089I2656J-2656D01*
G01D02*
X113099D01*
G01D02*
G03X115299Y956289I0J2200D01*
G01D02*
Y990050D01*
G01X113999Y975102D02*
G03X113749Y975352I-250J0D01*
G01D02*
G02X113499Y975602I0J250D01*
G01D02*
Y977502D01*
G01D02*
G02X113749Y977752I250J0D01*
G01D02*
G03X113999Y978002I0J250D01*
G01D02*
Y979421D01*
G01D02*
G03X113599Y979821I-400J0D01*
G01D02*
G02X113199Y980221I0J400D01*
G01D02*
Y981821D01*
G01D02*
G02X113599Y982221I400J0D01*
G01D02*
G03X113999Y982621I0J400D01*
G01D02*
Y990049D01*
G01D02*
G03X111762Y995446I-7632J-1D01*
G01X115299Y990050D02*
G03X112682Y996366I-8933J-1D01*
G01X121399Y994946D02*
G03X120079Y998131I-4504J0D01*
G01X122699Y994947D02*
G03X120999Y999051I-5804J0D01*
G01X116877Y997671D02*
G02X118999Y992550I-5121J-5122D01*
G01X115957Y996751D02*
G02X117699Y992549I-4200J-4203D01*
G01X123641Y1000068D02*
G02X125099Y996550I-3518J-3519D01*
G01X124803Y1037979D02*
X124615Y1038168D01*
G01X125999Y1052550D02*
G02X124099Y1050650I-1900J0D01*
G01D02*
X123999D01*
G01X124583Y1055006D02*
G02X124116Y1054176I-2275J733D01*
G01D02*
G02X123999Y1054050I-1809J1562D01*
G01X124423Y1081177D02*
X124752Y1080849D01*
G01X124423Y1077523D02*
X124752Y1077851D01*
G01X104078Y1336952D02*
X104598Y1336433D01*
G01D02*
G03X105999Y1335852I1402J1401D01*
G01D02*
X106999D01*
G01D02*
G03X108690Y1336553I-1J2392D01*
G01D02*
X109228Y1337090D01*
G01X104078Y1333452D02*
X104598Y1333971D01*
G01D02*
G02X105999Y1334552I1402J-1401D01*
G01D02*
X106999D01*
G01D02*
G02X108693Y1333851I1J-2395D01*
G01D02*
X109228Y1333315D01*
G01X107578Y1361952D02*
X107837D01*
G01D02*
G02X108280Y1361769I1J-626D01*
G01D02*
X108647Y1361402D01*
G01D02*
G03X109975Y1360852I1328J1328D01*
G01D02*
X111314D01*
G01D02*
G03X112999Y1361550I0J2383D01*
G01X107578Y1358452D02*
Y1358540D01*
G01D02*
G02X107641Y1358692I214J0D01*
G01D02*
X108039Y1359090D01*
G01D02*
G02X109154Y1359552I1115J-1114D01*
G01D02*
X110603D01*
G01D02*
G02X112300Y1358849I0J-2400D01*
G01D02*
X112440Y1358709D01*
G01D02*
Y1358196D01*
G01X104078Y1361952D02*
X103509Y1361383D01*
G01X104078Y1358452D02*
X103547Y1358983D01*
G01X103500Y1347000D02*
G03X105378Y1347778I0J2656D01*
G01D02*
X105700Y1348100D01*
G01X104000Y1345500D02*
G02X105365Y1344934I-1J-1931D01*
G01D02*
X105700Y1344600D01*
G01X109200Y1348100D02*
X109452Y1347849D01*
G01D02*
G03X111500Y1347000I2049J2048D01*
G01D02*
G03X112944Y1347598I0J2042D01*
G01D02*
X113500Y1348154D01*
G01Y1344500D02*
X113207Y1344793D01*
G01D02*
G03X111500Y1345500I-1707J-1707D01*
G01D02*
X111373D01*
G01D02*
G03X109200Y1344600I0J-3073D01*
G01X105904Y1421955D02*
X253663Y1274195D01*
G01X104984Y1421035D02*
X252743Y1273275D01*
G01X257111Y1274142D02*
X107602Y1423653D01*
G01X258032Y1275063D02*
X108522Y1424573D01*
G01D02*
X103932Y1429160D01*
G01X117390Y1426201D02*
X117945Y1426756D01*
G01D02*
G02X119283Y1427310I1338J-1339D01*
G01X124799Y1443085D02*
G03X124443Y1443112I-359J-2373D01*
G01D02*
X106857D01*
G01D02*
G03X105498Y1442549I0J-1922D01*
G01D02*
X105413Y1442464D01*
G01D02*
G03X104935Y1441310I1154J-1154D01*
G01D02*
Y1440634D01*
G01X127078Y1444412D02*
X105902D01*
G01D02*
G02X105264Y1444676I0J903D01*
G01D02*
X104999Y1444941D01*
G01X125353Y1428610D02*
X119283D01*
G01D02*
G02X117945Y1429164I0J1893D01*
G01D02*
X117572Y1429538D01*
G01D02*
G02X117390Y1429976I438J439D01*
G01X119283Y1427310D02*
X143574D01*
G01X125794Y1466850D02*
G03X124297Y1466230I0J-2117D01*
G01D02*
G03X123808Y1465050I1179J-1180D01*
G01X124290Y1469241D02*
X127640D01*
G01X105249Y1743050D02*
X105395Y1742905D01*
G01D02*
G03X107699Y1741950I2305J2304D01*
G01D02*
G03X108041Y1742091I1J483D01*
G01D02*
X109499Y1743550D01*
G01X105249Y1739550D02*
X105395Y1739695D01*
G01D02*
G02X107699Y1740650I2305J-2304D01*
G01D02*
G02X109079Y1740079I1J-1951D01*
G01D02*
X109399Y1739758D01*
G01D02*
Y1739550D01*
G01X107249Y1764050D02*
X107617Y1764417D01*
G01D02*
G02X109127Y1765136I1768J-1768D01*
G01D02*
G02X109385Y1765150I264J-2486D01*
G01D02*
X109863D01*
G01D02*
G03X112551Y1766262I1J3802D01*
G01X107249Y1767550D02*
X107279Y1767521D01*
G01D02*
G03X109863Y1766450I2585J2584D01*
G01D02*
G03X111631Y1767182I0J2501D01*
G01D02*
X111867Y1767418D01*
G01D02*
G03X112599Y1769186I-1769J1768D01*
G01D02*
Y1775826D01*
G01D02*
G03X111867Y1777594I-2501J0D01*
G01X112551Y1766262D02*
X112787Y1766498D01*
G01D02*
G03X113899Y1769186I-2690J2687D01*
G01D02*
Y1775826D01*
G01D02*
G03X112787Y1778514I-3802J1D01*
G01X125986Y1847230D02*
X113843D01*
G01D02*
G02X108070Y1849621I-1J8163D01*
G01D02*
X108069Y1849620D01*
G01X125499Y1848530D02*
X113842D01*
G01D02*
G02X108989Y1850540I0J6863D01*
G01X112535Y1836586D02*
G03X118484Y1834122I5949J5949D01*
G01D02*
X144457D01*
G01X111615Y1835666D02*
X111616Y1835667D01*
G01D02*
G03X118485Y1832822I6868J6868D01*
G01D02*
X143899D01*
G01X124999Y1871750D02*
G03X123779Y1871244I1J-1726D01*
G01D02*
X123393Y1870859D01*
G01X125299Y1873154D02*
G02X124263Y1873583I0J1465D01*
G01D02*
X123592Y1874254D01*
G01X127983Y214567D02*
G03X134000Y212074I6017J6015D01*
G01D02*
X144590D01*
G01D02*
G03X144990Y212474I0J400D01*
G01D02*
Y213524D01*
G01D02*
G02X145390Y213924I400J0D01*
G01D02*
X145403Y213937D01*
G01D02*
X150591D01*
G01X127063Y213647D02*
G03X133999Y210774I6936J6936D01*
G01D02*
X144590D01*
G01D02*
G02X144990Y210374I0J-400D01*
G01D02*
Y209324D01*
G01D02*
G03X145390Y208924I400J0D01*
G01D02*
X145403Y208937D01*
G01D02*
X150591D01*
G01X128249Y224550D02*
G03X125401Y225397I-2640J-3664D01*
G01D02*
X125002Y225379D01*
G01D02*
X124999Y225378D01*
G01D02*
Y225375D01*
G01X128249Y228050D02*
G02X124939Y226680I-3548J3890D01*
G01D02*
G02X124701Y226675I-230J5260D01*
G01X131749Y224550D02*
G02X134704Y225774I2955J-2955D01*
G01D02*
X144590D01*
G01D02*
G02X144990Y225374I0J-400D01*
G01D02*
Y224324D01*
G01D02*
G03X145390Y223924I400J0D01*
G01D02*
X145403Y223937D01*
G01D02*
X150591D01*
G01X131749Y228050D02*
G03X134105Y227074I2356J2356D01*
G01D02*
X144590D01*
G01D02*
G03X144990Y227474I0J400D01*
G01D02*
Y228524D01*
G01D02*
G02X145390Y228924I400J0D01*
G01D02*
X145403Y228937D01*
G01D02*
X150591D01*
G01X128249Y249050D02*
G03X127042Y249550I-1207J-1207D01*
G01X128249Y252550D02*
X126874Y251175D01*
G01D02*
G02X126089Y250850I-785J785D01*
G01X131749Y249050D02*
X131786Y249086D01*
G01D02*
G02X134031Y250150I2613J-2613D01*
G01D02*
G02X134251Y250166I378J-3676D01*
G01D02*
G02X134399Y250169I149J-3693D01*
G01D02*
X153000D01*
G01X131749Y252550D02*
Y252066D01*
G01D02*
G03X131924Y251644I596J0D01*
G01D02*
G03X132346Y251469I422J421D01*
G01D02*
X152744D01*
G01X129999Y493550D02*
G03X131100Y496208I-2658J2658D01*
G01D02*
Y609384D01*
G01X130919Y492630D02*
G03X132400Y496207I-3579J3577D01*
G01D02*
Y609385D01*
G01X128700Y497982D02*
G02X127590Y495302I-3791J0D01*
G01X127400Y497983D02*
G02X126670Y496222I-2491J1D01*
G01X124999Y502295D02*
Y606007D01*
G01X128700Y607167D02*
Y497982D01*
G01X127400Y607166D02*
Y497983D01*
G01X126143Y623244D02*
X126144D01*
G01D02*
X130168Y619220D01*
G01D02*
G03X134113Y617586I3945J3945D01*
G01D02*
X144590D01*
G01D02*
G03X144990Y617986I0J400D01*
G01D02*
Y619036D01*
G01D02*
G02X145390Y619436I400J0D01*
G01D02*
X145403Y619449D01*
G01D02*
X150591D01*
G01X129248Y618300D02*
X129249Y618301D01*
G01D02*
G03X134114Y616286I4864J4864D01*
G01D02*
X144590D01*
G01D02*
G02X144990Y615886I0J-400D01*
G01D02*
Y614836D01*
G01D02*
G03X145390Y614436I400J0D01*
G01D02*
X145403Y614449D01*
G01D02*
X150591D01*
G01X131100Y609384D02*
G03X130182Y611600I-3134J0D01*
G01X132400Y609385D02*
G03X131101Y612519I-4434J-2D01*
G01D02*
X131102Y612520D01*
G01X126918Y611469D02*
G02X128700Y607167I-4302J-4302D01*
G01X125998Y610549D02*
X125999Y610550D01*
G01D02*
G02X127400Y607166I-3383J-3383D01*
G01X125227Y635822D02*
X125499Y635550D01*
G01X131688Y630065D02*
G03X129093Y631140I-2595J-2595D01*
G01X131688Y633565D02*
X131669Y633546D01*
G01D02*
G02X128999Y632440I-2670J2670D01*
G01X135188Y630065D02*
X135284Y630162D01*
G01D02*
G02X137999Y631286I2714J-2715D01*
G01D02*
X144590D01*
G01D02*
G02X144990Y630886I0J-400D01*
G01D02*
Y629836D01*
G01D02*
G03X145390Y629436I400J0D01*
G01D02*
X145403Y629449D01*
G01D02*
X150591D01*
G01X135188Y633565D02*
G03X137552Y632586I2364J2364D01*
G01D02*
X144590D01*
G01D02*
G03X144990Y632986I0J400D01*
G01D02*
Y634036D01*
G01D02*
G02X145390Y634436I400J0D01*
G01D02*
X145403Y634449D01*
G01D02*
X150591D01*
G01X131400Y644600D02*
Y645102D01*
G01D02*
G03X130595Y647045I-2748J0D01*
G01D02*
X129931Y647708D01*
G01D02*
X127794Y649845D01*
G01D02*
Y649846D01*
G01D02*
X127795Y649847D01*
G01D02*
X127655Y649987D01*
G01D02*
G02X126799Y652051I2061J2064D01*
G01D02*
Y653298D01*
G01D02*
G02X127517Y655031I2451J0D01*
G01D02*
G02X128770Y655550I1253J-1253D01*
G01D02*
X129499D01*
G01D02*
G02X131555Y654699I1J-2907D01*
G01D02*
X131688Y654565D01*
G01Y658065D02*
X131161Y657539D01*
G01D02*
G02X129499Y656850I-1663J1662D01*
G01D02*
X128771D01*
G01D02*
G03X126598Y655950I-1J-3072D01*
G01D02*
X126597D01*
G01D02*
G03X125499Y653299I2653J-2652D01*
G01D02*
Y652050D01*
G01D02*
G03X126735Y649067I4218J0D01*
G01D02*
X126875Y648927D01*
G01D02*
X126874Y648925D01*
G01D02*
X128374Y647425D01*
G01D02*
G02X128591Y647108I-752J-747D01*
G01D02*
G02X128592Y647105I-1005J-337D01*
G01D02*
G02X128643Y646968I-965J-437D01*
G01D02*
G02X128657Y646433I-1019J-294D01*
G01D02*
G02X128374Y645925I-1033J242D01*
G01D02*
X127999Y645550D01*
G01X135188Y654565D02*
G02X138773Y656050I3585J-3585D01*
G01D02*
X153999D01*
G01X135188Y658065D02*
G03X136914Y657350I1726J1726D01*
G01D02*
X153999D01*
G01X144238Y649131D02*
G03X145519Y647850I1281J0D01*
G01D02*
X153633D01*
G01X144238Y645356D02*
G02X145432Y646550I1194J0D01*
G01D02*
X153199D01*
G01X125579Y727970D02*
X142196Y744587D01*
G01X126499Y727050D02*
X143116Y743667D01*
G01X145698Y739349D02*
X145699D01*
G01D02*
X146269Y739919D01*
G01X147300Y745550D02*
G02X145349Y740839I-6663J0D01*
G01D02*
X145160Y740649D01*
G01D02*
X145159D01*
G01X142196Y744587D02*
G03X143600Y747974I-3387J3388D01*
G01D02*
Y750501D01*
G01X143116Y743667D02*
G03X144900Y747974I-4307J4307D01*
G01D02*
Y751040D01*
G01X141199Y1002551D02*
Y749507D01*
G01D02*
G02X139603Y745654I-5449J0D01*
G01X139899Y1002550D02*
Y749507D01*
G01D02*
G02X138683Y746574I-4148J1D01*
G01X135872Y749263D02*
G03X136199Y750050I-787J788D01*
G01D02*
Y1001050D01*
G01X136792Y748343D02*
G03X137499Y750050I-1707J1707D01*
G01D02*
Y1001049D01*
G01X133799Y752550D02*
G02X132712Y749923I-3715J-1D01*
G01X127128Y751520D02*
G03X128799Y755551I-4029J4032D01*
G01D02*
Y997050D01*
G01X128048Y750600D02*
G03X130099Y755550I-4950J4951D01*
G01D02*
Y997051D01*
G01X126399Y996551D02*
Y757050D01*
G01D02*
G02X124914Y753465I-5070J0D01*
G01X125099Y996550D02*
Y757050D01*
G01X143600Y750501D02*
X143599Y750502D01*
G01D02*
Y1004627D01*
G01X144900Y751040D02*
X144899Y751041D01*
G01D02*
Y1004628D01*
G01X133799Y999051D02*
Y752550D01*
G01X132499Y999050D02*
Y752550D01*
G01D02*
G02X131792Y750843I-2414J0D01*
G01X128799Y997050D02*
G03X126536Y1002512I-7725J-1D01*
G01X130099Y997051D02*
G03X127456Y1003432I-9025J0D01*
G01X124561Y1000988D02*
G02X126399Y996551I-4438J-4438D01*
G01X138274Y1009614D02*
G02X141199Y1002551I-7065J-7063D01*
G01X137354Y1008694D02*
G02X139899Y1002550I-6144J-6144D01*
G01X136199Y1001050D02*
G03X133867Y1006681I-7964J0D01*
G01X137499Y1001049D02*
G03X134787Y1007601I-9265J3D01*
G01X131184Y1005364D02*
G02X133799Y999051I-6314J-6314D01*
G01X130264Y1004444D02*
G02X132499Y999050I-5394J-5395D01*
G01X133521Y1025367D02*
G03X138999Y1023098I5478J5478D01*
G01D02*
X144590D01*
G01D02*
G03X144990Y1023498I0J400D01*
G01D02*
Y1024548D01*
G01D02*
G02X145390Y1024948I400J0D01*
G01D02*
X145403Y1024961D01*
G01D02*
X150591D01*
G01X132601Y1024447D02*
G03X139000Y1021798I6397J6399D01*
G01D02*
X144590D01*
G01D02*
G02X144990Y1021398I0J-400D01*
G01D02*
Y1020348D01*
G01D02*
G03X145390Y1019948I400J0D01*
G01D02*
X145403Y1019961D01*
G01D02*
X150591D01*
G01X143599Y1004627D02*
G03X141249Y1010300I-8023J0D01*
G01X144899Y1004628D02*
G03X142168Y1011219I-9323J-2D01*
G01D02*
X142169Y1011220D01*
G01X129249Y1035550D02*
G02X125802Y1036978I0J4874D01*
G01D02*
X125541Y1037239D01*
G01D02*
X124931Y1037850D01*
G01D02*
X124803Y1037979D01*
G01X124615Y1038168D02*
Y1038167D01*
G01X129249Y1039050D02*
X128967Y1038768D01*
G01D02*
G02X125853I-1557J1557D01*
G01D02*
X125723Y1038899D01*
G01X132749Y1035550D02*
G02X134546Y1036621I3013J-3013D01*
G01D02*
G02X134835Y1036696I1214J-4084D01*
G01D02*
G02X135762Y1036798I927J-4159D01*
G01D02*
X144590D01*
G01D02*
G02X144990Y1036398I0J-400D01*
G01D02*
Y1035348D01*
G01D02*
G03X145390Y1034948I400J0D01*
G01D02*
X145403Y1034961D01*
G01D02*
X150591D01*
G01X132749Y1039050D02*
G03X134063Y1038248I2313J2313D01*
G01D02*
X134303Y1038171D01*
G01D02*
G03X134514Y1038138I211J657D01*
G01D02*
G03X135062Y1038092I547J3225D01*
G01D02*
X135497D01*
G01D02*
G02X135762Y1038098I258J-5555D01*
G01D02*
X144590D01*
G01D02*
G03X144990Y1038498I0J400D01*
G01D02*
Y1039548D01*
G01D02*
G02X145390Y1039948I400J0D01*
G01D02*
X145403Y1039961D01*
G01D02*
X150591D01*
G01X129249Y1060050D02*
X128206D01*
G01D02*
G03X126999Y1059550I0J-1707D01*
G01D02*
G03X125999Y1057136I2414J-2414D01*
G01D02*
Y1052550D01*
G01X129249Y1063550D02*
X126073Y1060374D01*
G01D02*
G03X124699Y1057057I3317J-3317D01*
G01D02*
Y1055740D01*
G01D02*
G02X124583Y1055006I-2390J2D01*
G01X132749Y1060050D02*
X133247Y1060547D01*
G01D02*
G02X135399Y1061439I2153J-2152D01*
G01D02*
X153583D01*
G01X132749Y1063550D02*
G03X134707Y1062739I1958J1958D01*
G01D02*
X153124D01*
G01X137477Y1081177D02*
X136759Y1080460D01*
G01D02*
G02X135650Y1080000I-1110J1109D01*
G01D02*
X135250D01*
G01D02*
G02X132774Y1081025I-1J3501D01*
G01D02*
X132700Y1081100D01*
G01X137481Y1077557D02*
X136825Y1078214D01*
G01D02*
G03X135650Y1078700I-1174J-1175D01*
G01D02*
X135250D01*
G01D02*
G03X132774Y1077675I-1J-3501D01*
G01D02*
X132700Y1077600D01*
G01X124752Y1080849D02*
G03X126800Y1080000I2049J2048D01*
G01D02*
G03X129019Y1080919I0J3138D01*
G01D02*
X129200Y1081100D01*
G01X124752Y1077851D02*
G02X126800Y1078700I2049J-2048D01*
G01D02*
G02X129019Y1077781I0J-3138D01*
G01D02*
X129200Y1077600D01*
G01X143574Y1427310D02*
G02X144499Y1426385I0J-925D01*
G01D02*
G03X145424Y1425460I925J0D01*
G01D02*
X145437Y1425473D01*
G01D02*
X150591D01*
G01X127640Y1441241D02*
X127474D01*
G01D02*
G02X127191Y1441358I0J401D01*
G01D02*
X126140Y1442409D01*
G01D02*
G03X124799Y1443085I-1696J-1697D01*
G01X127640Y1444741D02*
X127475Y1444576D01*
G01D02*
G02X127078Y1444412I-397J399D01*
G01X131140Y1441241D02*
X131674Y1441775D01*
G01D02*
G02X132965Y1442310I1291J-1290D01*
G01D02*
X144074D01*
G01D02*
G02X144999Y1441385I0J-925D01*
G01D02*
G03X145924Y1440460I925J0D01*
G01X131140Y1444741D02*
Y1444605D01*
G01D02*
G03X131236Y1444373I328J0D01*
G01D02*
X131570Y1444040D01*
G01D02*
G03X132606Y1443610I1037J1036D01*
G01D02*
X144074D01*
G01D02*
G03X144999Y1444535I0J925D01*
G01D02*
G02X145924Y1445460I925J0D01*
G01X146732Y1430460D02*
G03X144499Y1429535I0J-3158D01*
G01D02*
X143980Y1429017D01*
G01D02*
G02X142999Y1428610I-982J981D01*
G01D02*
X128243D01*
G01D02*
G02X127998Y1428855I0J245D01*
G01D02*
G03X127753Y1429100I-245J0D01*
G01D02*
X125843D01*
G01D02*
G03X125598Y1428855I0J-245D01*
G01D02*
G02X125353Y1428610I-245J0D01*
G01X127640Y1465741D02*
X126907Y1466474D01*
G01D02*
G03X125999Y1466850I-908J-908D01*
G01D02*
X125794D01*
G01X131140Y1465741D02*
G02X134216Y1467015I3076J-3076D01*
G01D02*
X152056D01*
G01X131140Y1469241D02*
G03X133376Y1468315I2236J2236D01*
G01D02*
X152507D01*
G01X142900Y1460000D02*
G03X145676Y1458850I2776J2776D01*
G01D02*
X153106D01*
G01X142999Y1456373D02*
X143452Y1456827D01*
G01D02*
G02X145199Y1457550I1746J-1747D01*
G01D02*
X153019D01*
G01X135876Y1810172D02*
G03X142930Y1807250I7054J7054D01*
G01D02*
X258262D01*
G01X264482Y1819550D02*
X134898D01*
G01D02*
G02X134897Y1819549I-4093J4092D01*
G01D02*
X134896Y1819550D01*
G01D02*
G02X130804Y1821245I0J5787D01*
G01D02*
X130498Y1821551D01*
G01D02*
X130021Y1822029D01*
G01D02*
G03X127999Y1822867I-2023J-2023D01*
G01D02*
Y1822866D01*
G01X264481Y1820850D02*
X134897D01*
G01D02*
G02X131723Y1822165I0J4487D01*
G01D02*
X131418Y1822470D01*
G01D02*
X130941Y1822948D01*
G01D02*
G03X127999Y1824166I-2941J-2942D01*
G01X124599Y1820466D02*
G02X129418Y1818470I0J-6815D01*
G01D02*
X136796Y1811092D01*
G01D02*
G03X142931Y1808550I6135J6133D01*
G01D02*
X258261D01*
G01X124599Y1819166D02*
G02X128498Y1817550I-1J-5514D01*
G01D02*
X135876Y1810172D01*
G01X128342Y1846254D02*
G03X125986Y1847230I-2356J-2356D01*
G01X128342Y1849754D02*
X128263Y1849675D01*
G01D02*
G02X125499Y1848530I-2764J2764D01*
G01X131842Y1846254D02*
G02X135627Y1847822I3785J-3785D01*
G01D02*
X144590D01*
G01D02*
G02X144990Y1847422I0J-400D01*
G01D02*
Y1846372D01*
G01D02*
G03X145390Y1845972I400J0D01*
G01D02*
X145403Y1845985D01*
G01D02*
X150591D01*
G01X131842Y1849754D02*
G03X133368Y1849122I1526J1526D01*
G01D02*
X144590D01*
G01D02*
G03X144990Y1849522I0J400D01*
G01D02*
Y1850572D01*
G01X144457Y1834122D02*
G03X144999Y1834664I0J542D01*
G01D02*
Y1835372D01*
G01D02*
G02X145599Y1835972I600J0D01*
G01D02*
X145612Y1835985D01*
G01D02*
X150591D01*
G01X143899Y1832822D02*
G02X143927Y1832821I-7J-600D01*
G01D02*
G02X143929I1J-600D01*
G01D02*
G02X144090Y1832790I-32J-599D01*
G01D02*
X144091D01*
G01D02*
Y1832789D01*
G01D02*
G02X144499Y1832222I-190J-567D01*
G01D02*
Y1831572D01*
G01D02*
G03X145099Y1830972I600J0D01*
G01D02*
X145112Y1830985D01*
G01D02*
X150591D01*
G01X128342Y1870754D02*
X128299Y1870798D01*
G01D02*
G03X125999Y1871750I-2299J-2300D01*
G01X144990Y1850572D02*
G02X145390Y1850972I400J0D01*
G01D02*
X145403Y1850985D01*
G01D02*
X150591D01*
G01X131842Y1870754D02*
X132211Y1871122D01*
G01D02*
G02X135129Y1872502I3388J-3388D01*
G01X137999Y1865151D02*
X138903Y1864247D01*
G01D02*
G03X139560Y1864093I453J454D01*
G01D02*
G02X141196Y1864376I1737J-5169D01*
G01D02*
G02X141296Y1864377I105J-5451D01*
G01D02*
X153247D01*
G01X137999Y1861497D02*
X138363Y1861861D01*
G01D02*
G02X141222Y1863076I2936J-2937D01*
G01D02*
G02X141299Y1863077I92J-4151D01*
G01D02*
X153280D01*
G01X125999Y1871750D02*
X124999D01*
G01X128342Y1874254D02*
X128121Y1874033D01*
G01D02*
G02X125999Y1873154I-2122J2122D01*
G01D02*
X125299D01*
G01X135129Y1872502D02*
G02X135599Y1872526I479J-4767D01*
G01D02*
X153034D01*
G01X131842Y1874254D02*
G03X132875Y1873826I1033J1033D01*
G01D02*
X153353D01*
G01X149999Y243504D02*
X150876Y242627D01*
G01D02*
G03X151536Y242331I718J717D01*
G01D02*
G03X151593Y242330I46J1013D01*
G01D02*
X153285D01*
G01D02*
G03X154157Y242691I0J1233D01*
G01D02*
X154457Y242991D01*
G01X149999Y239729D02*
X151067Y240796D01*
G01D02*
G02X151632Y241030I565J-565D01*
G01D02*
X153199D01*
G01D02*
G02X154218Y240608I0J-1441D01*
G01D02*
X154437Y240389D01*
G01D02*
G03X155123Y240105I686J686D01*
G01D02*
X155136Y240118D01*
G01D02*
X159055D01*
G01X153000Y250169D02*
G02X153649Y249900I0J-918D01*
G01D02*
G03X154484Y249554I835J835D01*
G01D02*
X154497Y249567D01*
G01D02*
X159055D01*
G01X152744Y251469D02*
G03X153557Y251702I0J1536D01*
G01D02*
G03X153830Y251919I-813J1303D01*
G01D02*
X154130Y252219D01*
G01D02*
X154201Y252289D01*
G01D02*
G02X155199Y252703I999J-998D01*
G01D02*
X155212Y252716D01*
G01D02*
X159055D01*
G01X154457Y242991D02*
G02X155092Y243254I635J-635D01*
G01D02*
X155105Y243267D01*
G01D02*
X159055D01*
G01X153999Y656050D02*
G02X154088Y656041I-6J-499D01*
G01D02*
G02X154499Y655550I-88J-491D01*
G01D02*
G03X154983Y655066I484J0D01*
G01D02*
X154996Y655079D01*
G01D02*
X159055D01*
G01X153999Y657350D02*
G03X154087Y657359I4J400D01*
G01D02*
G03X154399Y657750I-89J391D01*
G01D02*
G02X154864Y658215I465J0D01*
G01D02*
X154877Y658228D01*
G01D02*
X159055D01*
G01X153633Y647850D02*
G03X154599Y648250I0J1366D01*
G01D02*
G02X155845Y648766I1246J-1246D01*
G01D02*
X155858Y648779D01*
G01D02*
X159055D01*
G01X153199Y646550D02*
G02X154564Y645984I-1J-1931D01*
G01D02*
G03X155450Y645617I886J886D01*
G01D02*
X155463Y645630D01*
G01D02*
X159055D01*
G01X146269Y739919D02*
G03X148600Y745551I-5633J5630D01*
G01D02*
Y752574D01*
G01X147300Y752035D02*
Y745550D01*
G01X148600Y752574D02*
X148599Y752575D01*
G01D02*
Y982165D01*
G01X147299D02*
Y752036D01*
G01D02*
X147300Y752035D01*
G01X148599Y982165D02*
G02X149649Y984700I3585J0D01*
G01X148730Y985620D02*
G03X147299Y982165I3454J-3454D01*
G01X149649Y984700D02*
X166899Y1001950D01*
G01X167899Y1007504D02*
G02X165979Y1002869I-6555J0D01*
G01D02*
X148730Y985620D01*
G01X153583Y1061439D02*
G02X154293Y1061145I0J-1004D01*
G01D02*
X154543Y1060895D01*
G01D02*
G03X155308Y1060578I765J765D01*
G01D02*
X155321Y1060591D01*
G01D02*
X159055D01*
G01X153124Y1062739D02*
G03X153892Y1063057I0J1086D01*
G01D02*
X154242Y1063407D01*
G01D02*
G02X155015Y1063727I773J-773D01*
G01D02*
X155028Y1063740D01*
G01D02*
X159055D01*
G01X169199Y1051150D02*
G03X166799Y1053550I-2400J0D01*
G01D02*
X164494D01*
G01D02*
G02X163649Y1053900I0J1195D01*
G01D02*
G03X163299Y1054149I-913J-913D01*
G01D02*
G03X162988Y1054278I-311J-311D01*
G01D02*
X162975Y1054291D01*
G01D02*
X159055D01*
G01Y1051142D02*
X162609D01*
G01D02*
X162622Y1051129D01*
G01D02*
G03X163469Y1051480I0J1198D01*
G01D02*
X163919Y1051930D01*
G01D02*
G02X164692Y1052250I773J-773D01*
G01D02*
X166799D01*
G01D02*
G02X167899Y1051150I0J-1100D01*
G01X145924Y1440460D02*
X145937Y1440473D01*
G01D02*
X150591D01*
G01X145924Y1445460D02*
X145937Y1445473D01*
G01D02*
X150591D01*
G01Y1430473D02*
X146745D01*
G01D02*
X146732Y1430460D01*
G01X152056Y1467015D02*
G02X153550Y1466396I0J-2113D01*
G01D02*
G03X154289Y1466090I739J739D01*
G01D02*
X154302Y1466103D01*
G01D02*
X159055D01*
G01X152507Y1468315D02*
G03X153799Y1468850I0J1827D01*
G01D02*
G02X154738Y1469239I939J-939D01*
G01D02*
X154751Y1469252D01*
G01D02*
X159055D01*
G01X153106Y1458850D02*
G03X153710Y1459032I0J1093D01*
G01D02*
G03X153879Y1459170I-603J911D01*
G01D02*
X154129Y1459420D01*
G01D02*
G02X155022Y1459790I893J-893D01*
G01D02*
X155035Y1459803D01*
G01D02*
X159055D01*
G01X153019Y1457550D02*
G02X153994Y1457146I0J-1379D01*
G01D02*
G03X154436Y1456826I1219J1219D01*
G01D02*
G03X154883Y1456641I447J447D01*
G01D02*
X154896Y1456654D01*
G01D02*
X159055D01*
G01X153247Y1864377D02*
G03X154184Y1864765I0J1325D01*
G01D02*
X154384Y1864965D01*
G01D02*
G02X155198Y1865302I814J-814D01*
G01D02*
X155211Y1865315D01*
G01D02*
X159055D01*
G01X153280Y1863077D02*
G02X154161Y1862712I0J-1246D01*
G01D02*
G03X155511Y1862153I1350J1350D01*
G01D02*
X155524Y1862166D01*
G01D02*
X159055D01*
G01X153034Y1872526D02*
G02X154335Y1871987I0J-1840D01*
G01D02*
G03X155264Y1871602I929J929D01*
G01D02*
X155277Y1871615D01*
G01D02*
X159055D01*
G01X153353Y1873826D02*
G03X154109Y1874139I0J1069D01*
G01D02*
X154409Y1874439D01*
G01D02*
G02X155162Y1874751I753J-753D01*
G01D02*
X155175Y1874764D01*
G01D02*
X159055D01*
G01X166899Y1001950D02*
G03X169199Y1007503I-5555J5554D01*
G01D02*
Y1051150D01*
G01X167899D02*
Y1007504D01*
G01X206324Y1298375D02*
X207324Y1297376D01*
G01D02*
X207323D01*
G01D02*
X207704Y1296995D01*
G01D02*
Y1296987D01*
G01D02*
X207986Y1296705D01*
G01D02*
X207988D01*
G01D02*
X211071Y1293622D01*
G01X769378Y265673D02*
X216456Y1293223D01*
G01X770525Y266290D02*
X217719Y1293622D01*
G01X214286Y1291427D02*
X767356Y262675D01*
G01X213140Y1290811D02*
X766211Y262059D01*
G01X216456Y1293223D02*
G03X215718Y1294216I-3738J-2007D01*
G01D02*
X214747Y1295187D01*
G01D02*
X214569Y1295366D01*
G01X217719Y1293622D02*
X217717Y1293624D01*
G01D02*
X217601Y1293839D01*
G01D02*
G03X216638Y1295136I-4885J-2621D01*
G01D02*
X216111Y1295663D01*
G01D02*
X215668Y1296105D01*
G01D02*
X215490Y1296284D01*
G01X211991Y1294542D02*
G02X212018Y1294517I-311J-364D01*
G01D02*
G02X214131Y1291714I-7964J-8201D01*
G01D02*
X214132D01*
G01D02*
X214287Y1291427D01*
G01D02*
X214286D01*
G01X211071Y1293622D02*
G02X212985Y1291100I-7014J-7310D01*
G01D02*
X213140Y1290811D01*
G01X761700Y635902D02*
X250866Y1269918D01*
G01X240321Y1277068D02*
X771775Y618779D01*
G01X239352Y1276197D02*
X770761Y617961D01*
G01X762713Y636718D02*
X251835Y1270788D01*
G01X837846Y1037762D02*
X260462Y1271989D01*
G01D02*
G02X257111Y1274142I4055J9995D01*
G01X838335Y1038967D02*
X260918Y1273207D01*
G01D02*
G02X258032Y1275063I2829J7571D01*
G01X253663Y1274195D02*
X256810Y1271048D01*
G01D02*
G03X260310Y1268526I9515J9515D01*
G01D02*
X858139Y1023450D01*
G01X252743Y1273275D02*
X255889Y1270127D01*
G01D02*
X255891Y1270129D01*
G01D02*
G03X259729Y1267363I10435J10433D01*
G01D02*
G03X259947Y1267269I942J1884D01*
G01D02*
X857646Y1022247D01*
G01X258262Y1807250D02*
G03X265840Y1810389I0J10717D01*
G01X283574Y1834284D02*
X271919Y1822630D01*
G01D02*
G02X269157Y1820646I-7437J7438D01*
G01D02*
G02X264482Y1819550I-4675J9422D01*
G01X282654Y1835204D02*
X270999Y1823550D01*
G01D02*
G02X264481Y1820850I-6518J6518D01*
G01X258261Y1808550D02*
G03X264920Y1811309I0J9416D01*
G01D02*
G03X264922Y1811311I-6662J6664D01*
G01D02*
X284397Y1830786D01*
G01X265840Y1810389D02*
G03X265842Y1810391I-7582J7584D01*
G01D02*
X285317Y1829866D01*
G01X829300Y1836533D02*
X289000D01*
G01D02*
G03X283574Y1834284I1J-7673D01*
G01X829300Y1837833D02*
X288999D01*
G01D02*
G03X282654Y1835204I1J-8974D01*
G01X284397Y1830786D02*
G02X292463Y1834127I8066J-8066D01*
G01D02*
X292961D01*
G01D02*
G02X293356Y1834133I403J-13543D01*
G01D02*
X871582D01*
G01X285317Y1829866D02*
G02X292480Y1832833I7163J-7163D01*
G01D02*
X871216D01*
G01X826783Y1442443D02*
X327885Y1608910D01*
G01D02*
G03X324948Y1609408I-3385J-11053D01*
G01D02*
G03X324499Y1609417I-456J-11551D01*
G01X827206Y1443674D02*
X328287Y1610148D01*
G01D02*
G03X324999Y1610707I-3799J-12397D01*
G01D02*
G03X324500Y1610717I-507J-12850D01*
G01X322999Y1606849D02*
G02X327175Y1606183I1J-13418D01*
G01D02*
G02X327305Y1606139I-2144J-6549D01*
G01D02*
X734728Y1467421D01*
G01X322999Y1605549D02*
G02X326771Y1604947I0J-12118D01*
G01D02*
X734308Y1466189D01*
G01X734728Y1467421D02*
X847583Y1428996D01*
G01X734308Y1466189D02*
X847257Y1427733D01*
G01X841399Y228354D02*
X773381Y261431D01*
G01D02*
G02X769378Y265673I5884J9562D01*
G01X841950Y229532D02*
X773693Y262725D01*
G01D02*
G02X770623Y266107I5292J7888D01*
G01X767356Y262675D02*
Y262674D01*
G01D02*
G03X770002Y260069I5539J2980D01*
G01D02*
X791356Y249452D01*
G01X766211Y262059D02*
Y262058D01*
G01D02*
X766212Y262059D01*
G01D02*
G03X769405Y258914I6685J3593D01*
G01D02*
G03X769746Y258744I5594J10794D01*
G01D02*
X835499Y226050D01*
G01X770623Y266107D02*
X770526Y266287D01*
G01D02*
X770525Y266290D01*
G01X771775Y618779D02*
G03X774302Y617753I4930J8519D01*
G01D02*
G03X775141Y617586I2083J8272D01*
G01D02*
X872074D01*
G01X770761Y617961D02*
G03X774992Y616294I5621J8064D01*
G01D02*
X774999Y616293D01*
G01D02*
Y616286D01*
G01D02*
X872574D01*
G01X852999Y631482D02*
X774499D01*
G01D02*
G02X771374Y631719I-407J15349D01*
G01D02*
X767212Y632470D01*
G01D02*
G02X766919Y632527I302J2332D01*
G01D02*
G02X761701Y635903I2509J9599D01*
G01D02*
X761700Y635902D01*
G01X852999Y632782D02*
X774465D01*
G01D02*
G02X771604Y632998I-378J14050D01*
G01D02*
X767247Y633785D01*
G01D02*
G02X762713Y636718I2181J8342D01*
G01X791356Y249452D02*
X836007Y227247D01*
G01X845474Y227056D02*
G02X842305Y227933I14452J58384D01*
G01D02*
X842304Y227932D01*
G01D02*
X842208Y227962D01*
G01D02*
X841419Y228345D01*
G01D02*
X841399Y228354D01*
G01X845787Y228318D02*
G02X842685Y229176I14131J57124D01*
G01D02*
X841970Y229523D01*
G01D02*
X841950Y229532D01*
G01X836007Y227247D02*
X869979Y212832D01*
G01X835499Y226050D02*
X869147Y211770D01*
G01X850999Y1036992D02*
X842366D01*
G01D02*
Y1036993D01*
G01D02*
G02X837847Y1037763I-513J10635D01*
G01D02*
X837846Y1037762D01*
G01X851999Y1038292D02*
X842303D01*
G01D02*
G02X838335Y1038967I-453J9336D01*
G01X854144Y1441896D02*
X830499D01*
G01D02*
G02X826783Y1442443I0J12896D01*
G01X854144Y1443196D02*
X830499D01*
G01D02*
G02X827206Y1443674I0J11582D01*
G01X849501Y1848813D02*
G03X842248Y1845808I0J-10256D01*
G01D02*
X840520Y1844080D01*
G01D02*
X840519D01*
G01D02*
X835569Y1839128D01*
G01D02*
G02X829300Y1836534I-6266J6270D01*
G01D02*
Y1836533D01*
G01X849500Y1850113D02*
G03X841328Y1846728I0J-11557D01*
G01D02*
X839600Y1845000D01*
G01D02*
X834649Y1840048D01*
G01D02*
G02X829300Y1837833I-5348J5349D01*
G01X855728Y224924D02*
G02X853384Y225435I0J5632D01*
G01D02*
G03X852311Y225998I-1390J-1345D01*
G01D02*
G03X851999Y226024I-315J-1897D01*
G01D02*
X850999D01*
G01D02*
X845724Y227007D01*
G01D02*
G02X845474Y227056I373J2568D01*
G01X855728Y228424D02*
G03X853305Y227834I0J-5270D01*
G01D02*
G02X851999Y227324I-1306J1417D01*
G01D02*
X851120D01*
G01D02*
X845787Y228318D01*
G01X872148Y226024D02*
X862802D01*
G01D02*
G03X861474Y225474I0J-1878D01*
G01D02*
G02X860146Y224924I-1328J1328D01*
G01D02*
X859228D01*
G01X871996Y227324D02*
X863378D01*
G01D02*
G02X862050Y227874I0J1878D01*
G01D02*
G03X860722Y228424I-1328J-1328D01*
G01D02*
X859228D01*
G01X855728Y249424D02*
G03X854400Y249974I-1328J-1328D01*
G01D02*
X851278D01*
G01X855728Y252924D02*
X854841D01*
G01D02*
G03X847878Y250040I0J-9847D01*
G01X859228Y249424D02*
G02X861640Y250423I2412J-2412D01*
G01D02*
X881651D01*
G01X859228Y252924D02*
X859319Y252833D01*
G01D02*
G03X861850Y251725I2681J2680D01*
G01D02*
G03X861999Y251723I125J3789D01*
G01D02*
X881499D01*
G01X855946Y630382D02*
G03X852999Y631482I-2947J-3398D01*
G01X855946Y633882D02*
G02X852999Y632782I-2947J3398D01*
G01X859446Y630382D02*
G02X861499Y631286I2053J-1879D01*
G01D02*
X872074D01*
G01X859446Y633882D02*
G03X861499Y632586I2053J978D01*
G01D02*
X871574D01*
G01X855946Y654882D02*
X855261Y655567D01*
G01D02*
G03X854199Y656007I-1062J-1062D01*
G01D02*
X852560D01*
G01D02*
G03X851172Y655432I0J-1963D01*
G01X855946Y658382D02*
X855417Y657853D01*
G01D02*
G02X854099Y657307I-1318J1318D01*
G01D02*
X850676D01*
G01D02*
G03X849025Y656623I0J-2335D01*
G01D02*
X847772Y655370D01*
G01X859446Y654882D02*
X859706Y655141D01*
G01D02*
G02X861899Y656050I2194J-2193D01*
G01D02*
X882233D01*
G01X859446Y658382D02*
X859473Y658355D01*
G01D02*
G03X861899Y657350I2426J2426D01*
G01D02*
X882206D01*
G01X858139Y1023450D02*
X858138Y1023449D01*
G01D02*
G03X860351Y1023095I1863J4553D01*
G01D02*
X860396Y1023098D01*
G01D02*
X872074D01*
G01X857646Y1022247D02*
G03X860442Y1021798I2358J5754D01*
G01D02*
X872074D01*
G01X855583Y1035892D02*
G03X851881Y1036953I-4583J-9002D01*
G01D02*
G03X850999Y1036992I-887J-10062D01*
G01X855583Y1039392D02*
G02X851999Y1038292I-3584J5289D01*
G01X871180Y1036992D02*
X862770D01*
G01D02*
G03X861442Y1036442I0J-1878D01*
G01D02*
G02X860114Y1035892I-1328J1328D01*
G01D02*
X859083D01*
G01Y1039392D02*
X860330D01*
G01D02*
G02X861658Y1038842I0J-1878D01*
G01D02*
G03X862986Y1038292I1328J1328D01*
G01D02*
X871003D01*
G01X855583Y1060892D02*
X855320Y1061155D01*
G01D02*
G03X853299Y1061992I-2021J-2021D01*
G01D02*
X851384D01*
G01D02*
G03X850833Y1061441I0J-551D01*
G01X855583Y1064392D02*
X855108Y1063917D01*
G01D02*
G02X853599Y1063292I-1509J1509D01*
G01D02*
X850399D01*
G01D02*
G03X848067Y1062326I0J-3298D01*
G01D02*
X847233Y1061492D01*
G01X859083Y1060892D02*
G02X860558Y1061503I1475J-1475D01*
G01D02*
X881711D01*
G01X859083Y1064392D02*
G03X862919Y1062803I3836J3836D01*
G01D02*
X881489D01*
G01X857077Y1440796D02*
G03X854144Y1441896I-2933J-3360D01*
G01X857077Y1444296D02*
G02X854144Y1443196I-2933J3360D01*
G01X860577Y1440796D02*
X860742Y1440961D01*
G01D02*
G02X863999Y1442310I3257J-3257D01*
G01D02*
X872399D01*
G01X860577Y1444296D02*
G03X862999Y1443610I2422J3933D01*
G01D02*
X872399D01*
G01X847583Y1428996D02*
G03X849999Y1428610I2416J7368D01*
G01D02*
X872399D01*
G01X847257Y1427733D02*
G03X849999Y1427310I2742J8676D01*
G01D02*
X872399D01*
G01X857077Y1465796D02*
X856908Y1465964D01*
G01D02*
G03X854599Y1466921I-2310J-2309D01*
G01D02*
X853676D01*
G01D02*
G03X852288Y1466346I0J-1963D01*
G01X857077Y1469296D02*
X856994Y1469213D01*
G01D02*
G02X854599Y1468221I-2395J2395D01*
G01D02*
X852799D01*
G01D02*
G03X849227Y1466742I-1J-5051D01*
G01D02*
X848888Y1466402D01*
G01X860577Y1465796D02*
X860661Y1465880D01*
G01D02*
G02X863399Y1467014I2738J-2738D01*
G01D02*
X881279D01*
G01X860577Y1469296D02*
X860612Y1469262D01*
G01D02*
G03X862899Y1468314I2288J2287D01*
G01D02*
X881582D01*
G01X859064Y1846613D02*
X858537Y1847141D01*
G01D02*
G03X854499Y1848813I-4037J-4038D01*
G01D02*
X849501D01*
G01X859064Y1850113D02*
X849500D01*
G01X862564Y1846613D02*
G02X865483Y1847822I2919J-2919D01*
G01X862564Y1850113D02*
G03X864956Y1849122I2392J2392D01*
G01X859064Y1871113D02*
X857999D01*
G01D02*
G02X856688Y1871656I0J1854D01*
G01X854676Y1872213D02*
G03X853499Y1871036I0J-1177D01*
G01X851535Y1872493D02*
X850099Y1871056D01*
G01X862564Y1871113D02*
G02X865975Y1872526I3411J-3411D01*
G01X856688Y1871656D02*
X856396Y1871948D01*
G01D02*
G03X855756Y1872213I-640J-640D01*
G01D02*
X854676D01*
G01X859064Y1874613D02*
X857743D01*
G01D02*
G03X856869Y1874251I0J-1236D01*
G01D02*
X856578Y1873960D01*
G01D02*
G02X855499Y1873513I-1079J1079D01*
G01D02*
X853999D01*
G01D02*
G03X851535Y1872493I-1J-3484D01*
G01X862564Y1874613D02*
G03X863351Y1873826I787J0D01*
G01D02*
X881732D01*
G01X869979Y212832D02*
Y212831D01*
G01D02*
X870585Y212573D01*
G01D02*
X871191Y212317D01*
G01D02*
X871195Y212315D01*
G01D02*
X871336Y212255D01*
G01D02*
X871392Y212231D01*
G01D02*
G03X872371Y212421I349J820D01*
G01D02*
X872499Y212550D01*
G01D02*
X873494Y213545D01*
G01D02*
G02X874409Y213924I915J-915D01*
G01D02*
X874422Y213937D01*
G01D02*
X878937D01*
G01X869147Y211770D02*
X869470Y211634D01*
G01D02*
X869472Y211632D01*
G01D02*
X870684Y211121D01*
G01D02*
Y211120D01*
G01D02*
X870685Y211119D01*
G01D02*
X870828Y211057D01*
G01D02*
X870875Y211038D01*
G01D02*
X870878Y211037D01*
G01D02*
X870881Y211035D01*
G01D02*
X871140Y210925D01*
G01D02*
X871141D01*
G01D02*
X871143Y210924D01*
G01D02*
X871380Y210824D01*
G01D02*
X871527Y210761D01*
G01D02*
X871719Y210681D01*
G01D02*
X871998Y210565D01*
G01D02*
G02X872003Y210562I-882J-1476D01*
G01D02*
G02X872022Y210554I-662J-1599D01*
G01D02*
G02X872040Y210546I-694J-1587D01*
G01D02*
G02X872076Y210529I-722J-1575D01*
G01D02*
G02X872137Y210499I-734J-1569D01*
G01D02*
X872436Y210343D01*
G01D02*
G02X872899Y209577I-401J-765D01*
G01D02*
G03X873060Y209188I550J0D01*
G01D02*
G03X873699Y208924I638J639D01*
G01D02*
X873712Y208937D01*
G01D02*
X878937D01*
G01Y223937D02*
X875891D01*
G01D02*
G02X874477Y224523I0J1999D01*
G01D02*
X873562Y225438D01*
G01D02*
G03X872148Y226024I-1414J-1413D01*
G01X878937Y228937D02*
X875265D01*
G01D02*
G03X873851Y228351I0J-1999D01*
G01D02*
X873410Y227910D01*
G01D02*
G02X871996Y227324I-1414J1413D01*
G01X879192Y242764D02*
G03X880230Y242334I1038J1038D01*
G01D02*
X880399Y242330D01*
G01D02*
X881805D01*
G01D02*
G03X882381Y242568I1J814D01*
G01D02*
X882900Y243089D01*
G01X878078Y240103D02*
X878160Y240186D01*
G01D02*
G02X880199Y241030I2038J-2039D01*
G01D02*
X881886D01*
G01D02*
G02X882325Y240848I0J-621D01*
G01D02*
X882760Y240412D01*
G01D02*
X882761Y240410D01*
G01D02*
G03X883499Y240105I737J738D01*
G01D02*
X883512Y240118D01*
G01D02*
X887401D01*
G01X881651Y250423D02*
G02X882585Y250036I0J-1321D01*
G01D02*
G03X882826Y249837I1164J1164D01*
G01D02*
G03X883509Y249554I683J683D01*
G01D02*
X883522Y249567D01*
G01D02*
X887401D01*
G01X881499Y251723D02*
G03X882501Y252138I0J1417D01*
G01D02*
X882689Y252326D01*
G01D02*
G02X883599Y252703I910J-910D01*
G01D02*
X883612Y252716D01*
G01D02*
X887401D01*
G01X878078Y243878D02*
X879192Y242764D01*
G01X882900Y243089D02*
G02X883298Y243254I398J-398D01*
G01D02*
X883311Y243267D01*
G01D02*
X887401D01*
G01X872074Y617586D02*
G03X872999Y618511I0J925D01*
G01D02*
G02X873924Y619436I925J0D01*
G01D02*
X873937Y619449D01*
G01D02*
X878937D01*
G01X872574Y616286D02*
G02X873499Y615361I0J-925D01*
G01D02*
G03X874424Y614436I925J0D01*
G01D02*
X874437Y614449D01*
G01D02*
X878937D01*
G01X872074Y631286D02*
G02X872999Y630361I0J-925D01*
G01D02*
G03X873924Y629436I925J0D01*
G01D02*
X878924D01*
G01D02*
X878937Y629449D01*
G01X871574Y632586D02*
G03X872499Y633511I0J925D01*
G01D02*
G02X873424Y634436I925J0D01*
G01D02*
X878924D01*
G01D02*
X878937Y634449D01*
G01X882233Y656050D02*
G02X883199Y655650I0J-1366D01*
G01D02*
G03X884609Y655066I1410J1410D01*
G01D02*
X884622Y655079D01*
G01D02*
X887401D01*
G01X882206Y657350D02*
G03X882534Y657421I0J792D01*
G01D02*
G03X882766Y657582I-328J721D01*
G01D02*
G02X882880Y657688I1528J-1529D01*
G01D02*
G02X884152Y658215I1272J-1272D01*
G01D02*
X884165Y658228D01*
G01D02*
X887401D01*
G01X878596Y649348D02*
X879496Y648448D01*
G01D02*
G03X880376Y648052I961J961D01*
G01D02*
G03X880457Y648050I74J1357D01*
G01D02*
X882075D01*
G01D02*
G03X882799Y648350I0J1024D01*
G01D02*
G02X883803Y648766I1004J-1004D01*
G01D02*
X883816Y648779D01*
G01D02*
X887401D01*
G01X878596Y645573D02*
X879436Y646413D01*
G01D02*
G02X880250Y646750I814J-814D01*
G01D02*
X882004D01*
G01D02*
G02X882849Y646400I0J-1195D01*
G01D02*
X883149Y646100D01*
G01D02*
G03X884315Y645617I1166J1166D01*
G01D02*
X884328Y645630D01*
G01D02*
X887401D01*
G01X872074Y1023098D02*
G03X872999Y1024023I0J925D01*
G01D02*
G02X873924Y1024948I925J0D01*
G01D02*
X873937Y1024961D01*
G01D02*
X878937D01*
G01X872074Y1021798D02*
G02X872999Y1020873I0J-925D01*
G01D02*
G03X873924Y1019948I925J0D01*
G01D02*
X873937Y1019961D01*
G01D02*
X878937D01*
G01Y1034961D02*
X874867D01*
G01D02*
G02X873453Y1035547I0J1999D01*
G01D02*
X872594Y1036406D01*
G01D02*
G03X871180Y1036992I-1414J-1413D01*
G01X871003Y1038292D02*
G03X872417Y1038878I0J1999D01*
G01D02*
X872914Y1039375D01*
G01D02*
G02X874328Y1039961I1414J-1413D01*
G01D02*
X878937D01*
G01X881711Y1061503D02*
G02X882447Y1061198I0J-1041D01*
G01D02*
X882747Y1060898D01*
G01D02*
G03X883520Y1060578I773J773D01*
G01D02*
X883533Y1060591D01*
G01D02*
X887401D01*
G01X881489Y1062803D02*
G03X882604Y1063265I0J1576D01*
G01D02*
G02X883719Y1063727I1115J-1115D01*
G01D02*
X883732Y1063740D01*
G01D02*
X887401D01*
G01X877964Y1054485D02*
X878339Y1054111D01*
G01D02*
G03X880899Y1053050I2561J2560D01*
G01D02*
X881933D01*
G01D02*
G03X882017Y1053052I9J1366D01*
G01D02*
G03X882216Y1053079I-84J1364D01*
G01D02*
G03X882748Y1053300I-1J753D01*
G01D02*
X883149Y1053700D01*
G01D02*
X883349Y1053900D01*
G01D02*
G02X884262Y1054278I913J-913D01*
G01D02*
X884275Y1054291D01*
G01D02*
X887401D01*
G01X878233Y1051095D02*
G02X879814Y1051750I1581J-1581D01*
G01D02*
X883048D01*
G01D02*
G02X883475Y1051573I0J-604D01*
G01D02*
G03X883651Y1051422I1072J1072D01*
G01D02*
G03X884358Y1051129I707J707D01*
G01D02*
X884371Y1051142D01*
G01D02*
X887401D01*
G01X872399Y1427310D02*
G02X872999Y1426710I0J-600D01*
G01D02*
Y1426060D01*
G01D02*
G03X873599Y1425460I600J0D01*
G01D02*
X873612Y1425473D01*
G01D02*
X878937D01*
G01X872399Y1442310D02*
G02X872999Y1441710I0J-600D01*
G01D02*
Y1441060D01*
G01D02*
G03X873599Y1440460I600J0D01*
G01D02*
X873612Y1440473D01*
G01D02*
X878937D01*
G01X872399Y1443610D02*
G03X872999Y1444210I0J600D01*
G01D02*
Y1444860D01*
G01D02*
G02X873599Y1445460I600J0D01*
G01D02*
X873612Y1445473D01*
G01D02*
X878937D01*
G01X872399Y1428610D02*
G03X872999Y1429210I0J600D01*
G01D02*
Y1429860D01*
G01D02*
G02X873599Y1430460I600J0D01*
G01D02*
X873612Y1430473D01*
G01D02*
X878937D01*
G01X881279Y1467014D02*
G02X882752Y1466404I0J-2083D01*
G01D02*
G03X883510Y1466090I758J758D01*
G01D02*
X883523Y1466103D01*
G01D02*
X887401D01*
G01X881582Y1468314D02*
G03X882538Y1468710I0J1352D01*
G01D02*
G02X883815Y1469239I1277J-1277D01*
G01D02*
X883828Y1469252D01*
G01D02*
X887401D01*
G01X877853Y1459991D02*
G03X878978Y1458866I1125J0D01*
G01D02*
X881760D01*
G01D02*
G03X882412Y1459136I0J922D01*
G01D02*
X882689Y1459413D01*
G01D02*
G02X883599Y1459790I910J-910D01*
G01D02*
X883612Y1459803D01*
G01D02*
X887401D01*
G01X878054Y1456450D02*
G02X879170Y1457566I1116J0D01*
G01D02*
X881667D01*
G01D02*
G02X882478Y1457230I0J-1147D01*
G01D02*
X882778Y1456930D01*
G01D02*
G03X883476Y1456641I698J698D01*
G01D02*
X883489Y1456654D01*
G01D02*
X887401D01*
G01X865483Y1847822D02*
X872074D01*
G01D02*
G02X872999Y1846897I0J-925D01*
G01D02*
G03X873924Y1845972I925J0D01*
G01D02*
X878924D01*
G01D02*
X878937Y1845985D01*
G01X864956Y1849122D02*
X872574D01*
G01D02*
G03X873499Y1850047I0J925D01*
G01D02*
G02X874424Y1850972I925J0D01*
G01X871582Y1834133D02*
G03X871999Y1834550I0J417D01*
G01D02*
Y1835550D01*
G01D02*
G02X872421Y1835972I422J0D01*
G01D02*
X872434Y1835985D01*
G01D02*
X878937D01*
G01X871216Y1832833D02*
G02X871321Y1832825I-7J-782D01*
G01D02*
G02X871999Y1832050I-104J-775D01*
G01D02*
Y1831472D01*
G01D02*
G03X872499Y1830972I500J0D01*
G01D02*
X878924D01*
G01D02*
X878937Y1830985D01*
G01X874424Y1850972D02*
X874437Y1850985D01*
G01D02*
X878937D01*
G01X866914Y1865615D02*
G03X869099Y1864377I2185J1309D01*
G01D02*
X880999D01*
G01D02*
G03X882406Y1864669I1J3532D01*
G01D02*
G03X882457Y1864692I-1426J3231D01*
G01D02*
X882757Y1864992D01*
G01D02*
G02X883399Y1865302I642J-510D01*
G01D02*
X887388D01*
G01X866914Y1861840D02*
G02X868151Y1863077I1237J0D01*
G01D02*
X880999D01*
G01D02*
G02X882226Y1862803I-1J-2890D01*
G01D02*
G02X882684Y1862535I-1224J-2618D01*
G01D02*
G03X883499Y1862153I815J678D01*
G01D02*
X887388D01*
G01X865975Y1872526D02*
X881766D01*
G01D02*
G02X882408Y1872260I0J-908D01*
G01D02*
X882708Y1871960D01*
G01D02*
G03X883572Y1871602I864J864D01*
G01D02*
X887388D01*
G01X881732Y1873826D02*
G03X882432Y1874116I0J990D01*
G01D02*
X882632Y1874316D01*
G01D02*
G02X883682Y1874751I1050J-1050D01*
G01D02*
X887388D01*
G01Y1865302D02*
X887401Y1865315D01*
G01X887388Y1862153D02*
X887401Y1862166D01*
G01X887388Y1871602D02*
X887401Y1871615D01*
G01X887388Y1874751D02*
X887401Y1874764D01*
G54D12*
G01X1019291Y1620020D02*
Y1676496D01*
G02X1024213Y1681417I4921J0D01*
G01X1029528D01*
X1033465Y1685354D01*
Y1988189D01*
G03X1029528Y1992126I-3937J0D01*
G01X3937D01*
G03X0Y1988189I0J-3937D01*
G01Y1818701D01*
X3937Y1814764D01*
X19882D01*
G02Y1807283I0J-3740D01*
G01X3937D01*
X0Y1803346D01*
Y1409252D01*
X3937Y1405315D01*
X19882D01*
G02Y1397835I0J-3740D01*
G01X3937D01*
X0Y1393898D01*
Y834449D01*
X3937Y830512D01*
X19882D01*
G02Y823031I0J-3740D01*
G01X3937D01*
X0Y819094D01*
Y425000D01*
X3937Y421063D01*
X19882D01*
G02Y413583I0J-3740D01*
G01X3937D01*
X0Y409646D01*
Y3937D01*
G03X3937Y0I3937J0D01*
G01X1029528D01*
G03X1033465Y3937I0J3937D01*
G01Y1424882D01*
X1029528Y1428819D01*
X1024213D01*
G02X1019291Y1433740I-1J4921D01*
G01Y1607933D01*
X1015354Y1611870D01*
X989744D01*
G02Y1616083I0J2107D01*
G01X1015354D01*
X1019291Y1620020D01*
G01X24705Y1903150D02*
G02X10728I-6989J0D01*
G02X24705I6988J0D01*
G01X30639Y-130979D02*
Y-142979D01*
G01X28339Y-130979D02*
X32939D01*
G01X34939Y-142979D02*
Y-130979D01*
G01Y-136779D02*
X35439Y-135779D01*
X35939Y-135179D01*
X36739Y-134979D01*
X37339Y-135179D01*
X38039Y-135979D01*
X38339Y-137179D01*
Y-142979D01*
G01X42639Y-134979D02*
Y-142979D01*
G01Y-131779D02*
X42439Y-131579D01*
Y-131179D01*
X42639Y-130979D01*
X42839Y-131179D01*
Y-131579D01*
X42639Y-131779D01*
G01X47139Y-141579D02*
X47639Y-142379D01*
X48339Y-142979D01*
X48939D01*
X49539Y-142579D01*
X49939Y-141979D01*
X50139Y-141179D01*
X50039Y-139979D01*
X49639Y-139379D01*
X47839Y-138179D01*
X47439Y-136779D01*
X47639Y-135779D01*
X48039Y-135179D01*
X48639Y-134979D01*
X49239Y-135179D01*
X49839Y-135779D01*
G01X59239Y-145979D02*
X59939Y-146779D01*
X60739Y-146979D01*
X61439Y-146779D01*
X62039Y-145779D01*
X62439Y-144379D01*
Y-134979D01*
G01Y-136579D02*
X62039Y-135779D01*
X61439Y-135179D01*
X60739Y-134979D01*
X59939Y-135379D01*
X59439Y-136179D01*
X59039Y-137579D01*
X58839Y-138979D01*
X58939Y-140179D01*
X59339Y-141579D01*
X59939Y-142579D01*
X60739Y-142979D01*
X61339Y-142779D01*
X62039Y-141979D01*
X62439Y-141179D01*
G01X65139Y-137579D02*
X68339D01*
X68039Y-136179D01*
X67539Y-135379D01*
X66839Y-134979D01*
X66139Y-135179D01*
X65539Y-135779D01*
X65139Y-137179D01*
X64939Y-138379D01*
Y-139579D01*
X65139Y-140779D01*
X65639Y-141979D01*
X66239Y-142779D01*
X66939Y-142979D01*
X67639Y-142579D01*
X68339Y-141379D01*
G01X71239Y-142979D02*
Y-134979D01*
G01Y-136579D02*
X71739Y-135779D01*
X72239Y-135179D01*
X72939Y-134979D01*
X73439Y-135179D01*
X74039Y-135779D01*
G01X76839Y-142979D02*
Y-130979D01*
G01Y-136979D02*
X77339Y-135779D01*
X77939Y-135179D01*
X78539Y-134979D01*
X79439Y-135379D01*
X80039Y-136179D01*
X80439Y-137579D01*
Y-139179D01*
X80239Y-140779D01*
X79839Y-141979D01*
X79139Y-142779D01*
X78539Y-142979D01*
X77939Y-142779D01*
X77339Y-142179D01*
X76839Y-141179D01*
G01X83139Y-137579D02*
X86339D01*
X86039Y-136179D01*
X85539Y-135379D01*
X84839Y-134979D01*
X84139Y-135179D01*
X83539Y-135779D01*
X83139Y-137179D01*
X82939Y-138379D01*
Y-139579D01*
X83139Y-140779D01*
X83639Y-141979D01*
X84239Y-142779D01*
X84939Y-142979D01*
X85639Y-142579D01*
X86339Y-141379D01*
G01X89239Y-142979D02*
Y-134979D01*
G01Y-136579D02*
X89739Y-135779D01*
X90239Y-135179D01*
X90939Y-134979D01*
X91439Y-135179D01*
X92039Y-135779D01*
G01X102639Y-134979D02*
Y-142979D01*
G01Y-131779D02*
X102439Y-131579D01*
Y-131179D01*
X102639Y-130979D01*
X102839Y-131179D01*
Y-131579D01*
X102639Y-131779D01*
G01X107139Y-141579D02*
X107639Y-142379D01*
X108339Y-142979D01*
X108939D01*
X109539Y-142579D01*
X109939Y-141979D01*
X110139Y-141179D01*
X110039Y-139979D01*
X109639Y-139379D01*
X107839Y-138179D01*
X107439Y-136779D01*
X107639Y-135779D01*
X108039Y-135179D01*
X108639Y-134979D01*
X109239Y-135179D01*
X109839Y-135779D01*
G01X119039Y-145979D02*
X119739Y-146779D01*
X120339Y-146979D01*
X121139Y-146579D01*
X121739Y-145579D01*
X122039Y-143779D01*
Y-134979D01*
G01Y-131779D02*
X121839Y-131579D01*
Y-131179D01*
X122039Y-130979D01*
X122239Y-131179D01*
Y-131579D01*
X122039Y-131779D01*
G01X124939Y-134979D02*
Y-140579D01*
X125339Y-141979D01*
X125939Y-142779D01*
X126639Y-142979D01*
X127339Y-142779D01*
X127939Y-141979D01*
X128339Y-140579D01*
G01Y-142979D02*
Y-134979D01*
G01X131139Y-141579D02*
X131639Y-142379D01*
X132339Y-142979D01*
X132939D01*
X133539Y-142579D01*
X133939Y-141979D01*
X134139Y-141179D01*
X134039Y-139979D01*
X133639Y-139379D01*
X131839Y-138179D01*
X131439Y-136779D01*
X131639Y-135779D01*
X132039Y-135179D01*
X132639Y-134979D01*
X133239Y-135179D01*
X133839Y-135779D01*
G01X138639Y-130979D02*
Y-142979D01*
G01X137239Y-134979D02*
X140039D01*
G01X150039Y-142979D02*
Y-132779D01*
X150239Y-131779D01*
X150639Y-131179D01*
X151239Y-130979D01*
X151839Y-131379D01*
X152139Y-132379D01*
G01X150939Y-135779D02*
X148939D01*
G01X156639Y-142979D02*
X156039Y-142779D01*
X155439Y-141979D01*
X155039Y-140579D01*
X154839Y-138979D01*
X155039Y-137379D01*
X155439Y-135979D01*
X156039Y-135179D01*
X156639Y-134979D01*
X157239Y-135179D01*
X157839Y-135979D01*
X158239Y-137379D01*
X158339Y-138979D01*
X158239Y-140579D01*
X157839Y-141979D01*
X157239Y-142779D01*
X156639Y-142979D01*
G01X161239D02*
Y-134979D01*
G01Y-136579D02*
X161739Y-135779D01*
X162239Y-135179D01*
X162939Y-134979D01*
X163439Y-135179D01*
X164039Y-135779D01*
G01X172539Y-146579D02*
X173139Y-146979D01*
X173939Y-146579D01*
X174439Y-145779D01*
X174839Y-144779D01*
X175439Y-141579D01*
X176739Y-134979D01*
G01X173539D02*
X175439Y-141579D01*
G01X180639Y-142979D02*
X180039Y-142779D01*
X179439Y-141979D01*
X179039Y-140579D01*
X178839Y-138979D01*
X179039Y-137379D01*
X179439Y-135979D01*
X180039Y-135179D01*
X180639Y-134979D01*
X181239Y-135179D01*
X181839Y-135979D01*
X182239Y-137379D01*
X182339Y-138979D01*
X182239Y-140579D01*
X181839Y-141979D01*
X181239Y-142779D01*
X180639Y-142979D01*
G01X184939Y-134979D02*
Y-140579D01*
X185339Y-141979D01*
X185939Y-142779D01*
X186639Y-142979D01*
X187339Y-142779D01*
X187939Y-141979D01*
X188339Y-140579D01*
G01Y-142979D02*
Y-134979D01*
G01X197239Y-142979D02*
Y-134979D01*
G01Y-136579D02*
X197739Y-135779D01*
X198239Y-135179D01*
X198939Y-134979D01*
X199439Y-135179D01*
X200039Y-135779D01*
G01X203139Y-137579D02*
X206339D01*
X206039Y-136179D01*
X205539Y-135379D01*
X204839Y-134979D01*
X204139Y-135179D01*
X203539Y-135779D01*
X203139Y-137179D01*
X202939Y-138379D01*
Y-139579D01*
X203139Y-140779D01*
X203639Y-141979D01*
X204239Y-142779D01*
X204939Y-142979D01*
X205639Y-142579D01*
X206339Y-141379D01*
G01X210039Y-142979D02*
Y-132779D01*
X210239Y-131779D01*
X210639Y-131179D01*
X211239Y-130979D01*
X211839Y-131379D01*
X212139Y-132379D01*
G01X210939Y-135779D02*
X208939D01*
G01X215139Y-137579D02*
X218339D01*
X218039Y-136179D01*
X217539Y-135379D01*
X216839Y-134979D01*
X216139Y-135179D01*
X215539Y-135779D01*
X215139Y-137179D01*
X214939Y-138379D01*
Y-139579D01*
X215139Y-140779D01*
X215639Y-141979D01*
X216239Y-142779D01*
X216939Y-142979D01*
X217639Y-142579D01*
X218339Y-141379D01*
G01X221239Y-142979D02*
Y-134979D01*
G01Y-136579D02*
X221739Y-135779D01*
X222239Y-135179D01*
X222939Y-134979D01*
X223439Y-135179D01*
X224039Y-135779D01*
G01X227139Y-137579D02*
X230339D01*
X230039Y-136179D01*
X229539Y-135379D01*
X228839Y-134979D01*
X228139Y-135179D01*
X227539Y-135779D01*
X227139Y-137179D01*
X226939Y-138379D01*
Y-139579D01*
X227139Y-140779D01*
X227639Y-141979D01*
X228239Y-142779D01*
X228939Y-142979D01*
X229639Y-142579D01*
X230339Y-141379D01*
G01X232939Y-142979D02*
Y-134979D01*
G01Y-136979D02*
X233339Y-135979D01*
X233939Y-135179D01*
X234739Y-134979D01*
X235439Y-135179D01*
X236039Y-135979D01*
X236339Y-137379D01*
Y-142979D01*
G01X242239Y-135979D02*
X241539Y-135179D01*
X240939Y-134979D01*
X240139Y-135379D01*
X239539Y-136179D01*
X239139Y-137579D01*
X239039Y-138979D01*
X239139Y-140379D01*
X239539Y-141579D01*
X240139Y-142579D01*
X240939Y-142979D01*
X241639Y-142579D01*
X242239Y-141779D01*
G01X245139Y-137579D02*
X248339D01*
X248039Y-136179D01*
X247539Y-135379D01*
X246839Y-134979D01*
X246139Y-135179D01*
X245539Y-135779D01*
X245139Y-137179D01*
X244939Y-138379D01*
Y-139579D01*
X245139Y-140779D01*
X245639Y-141979D01*
X246239Y-142779D01*
X246939Y-142979D01*
X247639Y-142579D01*
X248339Y-141379D01*
G01X258639Y-130979D02*
Y-142979D01*
G01X257239Y-134979D02*
X260039D01*
G01X264639Y-142979D02*
X264039Y-142779D01*
X263439Y-141979D01*
X263039Y-140579D01*
X262839Y-138979D01*
X263039Y-137379D01*
X263439Y-135979D01*
X264039Y-135179D01*
X264639Y-134979D01*
X265239Y-135179D01*
X265839Y-135979D01*
X266239Y-137379D01*
X266339Y-138979D01*
X266239Y-140579D01*
X265839Y-141979D01*
X265239Y-142779D01*
X264639Y-142979D01*
G01X276039D02*
Y-132779D01*
X276239Y-131779D01*
X276639Y-131179D01*
X277239Y-130979D01*
X277839Y-131379D01*
X278139Y-132379D01*
G01X276939Y-135779D02*
X274939D01*
G01X282639Y-134979D02*
Y-142979D01*
G01Y-131779D02*
X282439Y-131579D01*
Y-131179D01*
X282639Y-130979D01*
X282839Y-131179D01*
Y-131579D01*
X282639Y-131779D01*
G01X286939Y-142979D02*
Y-134979D01*
G01Y-136979D02*
X287339Y-135979D01*
X287939Y-135179D01*
X288739Y-134979D01*
X289439Y-135179D01*
X290039Y-135979D01*
X290339Y-137379D01*
Y-142979D01*
G01X296439Y-130979D02*
Y-142979D01*
G01Y-141179D02*
X296039Y-142179D01*
X295439Y-142779D01*
X294739Y-142979D01*
X293939Y-142579D01*
X293339Y-141579D01*
X292939Y-140379D01*
X292839Y-138979D01*
X292939Y-137579D01*
X293339Y-136379D01*
X293939Y-135379D01*
X294739Y-134979D01*
X295439Y-135179D01*
X295939Y-135579D01*
X296439Y-136379D01*
G01X306639Y-130979D02*
Y-142979D01*
G01X305239Y-134979D02*
X308039D01*
G01X310939Y-142979D02*
Y-130979D01*
G01Y-136779D02*
X311439Y-135779D01*
X311939Y-135179D01*
X312739Y-134979D01*
X313339Y-135179D01*
X314039Y-135979D01*
X314339Y-137179D01*
Y-142979D01*
G01X317139Y-137579D02*
X320339D01*
X320039Y-136179D01*
X319539Y-135379D01*
X318839Y-134979D01*
X318139Y-135179D01*
X317539Y-135779D01*
X317139Y-137179D01*
X316939Y-138379D01*
Y-139579D01*
X317139Y-140779D01*
X317639Y-141979D01*
X318239Y-142779D01*
X318939Y-142979D01*
X319639Y-142579D01*
X320339Y-141379D01*
G01X332439Y-130979D02*
Y-142979D01*
G01Y-141179D02*
X332039Y-142179D01*
X331439Y-142779D01*
X330739Y-142979D01*
X329939Y-142579D01*
X329339Y-141579D01*
X328939Y-140379D01*
X328839Y-138979D01*
X328939Y-137579D01*
X329339Y-136379D01*
X329939Y-135379D01*
X330739Y-134979D01*
X331439Y-135179D01*
X331939Y-135579D01*
X332439Y-136379D01*
G01X336639Y-134979D02*
Y-142979D01*
G01Y-131779D02*
X336439Y-131579D01*
Y-131179D01*
X336639Y-130979D01*
X336839Y-131179D01*
Y-131579D01*
X336639Y-131779D01*
G01X342039Y-142979D02*
Y-132779D01*
X342239Y-131779D01*
X342639Y-131179D01*
X343239Y-130979D01*
X343839Y-131379D01*
X344139Y-132379D01*
G01X342939Y-135779D02*
X340939D01*
G01X348039Y-142979D02*
Y-132779D01*
X348239Y-131779D01*
X348639Y-131179D01*
X349239Y-130979D01*
X349839Y-131379D01*
X350139Y-132379D01*
G01X348939Y-135779D02*
X346939D01*
G01X353139Y-137579D02*
X356339D01*
X356039Y-136179D01*
X355539Y-135379D01*
X354839Y-134979D01*
X354139Y-135179D01*
X353539Y-135779D01*
X353139Y-137179D01*
X352939Y-138379D01*
Y-139579D01*
X353139Y-140779D01*
X353639Y-141979D01*
X354239Y-142779D01*
X354939Y-142979D01*
X355639Y-142579D01*
X356339Y-141379D01*
G01X359239Y-142979D02*
Y-134979D01*
G01Y-136579D02*
X359739Y-135779D01*
X360239Y-135179D01*
X360939Y-134979D01*
X361439Y-135179D01*
X362039Y-135779D01*
G01X365139Y-137579D02*
X368339D01*
X368039Y-136179D01*
X367539Y-135379D01*
X366839Y-134979D01*
X366139Y-135179D01*
X365539Y-135779D01*
X365139Y-137179D01*
X364939Y-138379D01*
Y-139579D01*
X365139Y-140779D01*
X365639Y-141979D01*
X366239Y-142779D01*
X366939Y-142979D01*
X367639Y-142579D01*
X368339Y-141379D01*
G01X370939Y-142979D02*
Y-134979D01*
G01Y-136979D02*
X371339Y-135979D01*
X371939Y-135179D01*
X372739Y-134979D01*
X373439Y-135179D01*
X374039Y-135979D01*
X374339Y-137379D01*
Y-142979D01*
G01X378639Y-130979D02*
Y-142979D01*
G01X377239Y-134979D02*
X380039D01*
G01X384639D02*
Y-142979D01*
G01Y-131779D02*
X384439Y-131579D01*
Y-131179D01*
X384639Y-130979D01*
X384839Y-131179D01*
Y-131579D01*
X384639Y-131779D01*
G01X392439Y-142979D02*
Y-134979D01*
G01Y-136379D02*
X392039Y-135579D01*
X391439Y-135179D01*
X390739Y-134979D01*
X390039Y-135379D01*
X389439Y-136179D01*
X389039Y-137379D01*
X388839Y-138979D01*
X389039Y-140579D01*
X389439Y-141779D01*
X390039Y-142579D01*
X390739Y-142979D01*
X391439Y-142779D01*
X392039Y-142179D01*
X392439Y-141379D01*
G01X396639Y-142979D02*
Y-130979D01*
G01X408639D02*
Y-142979D01*
G01X407239Y-134979D02*
X410039D01*
G01X413239Y-142979D02*
Y-134979D01*
G01Y-136579D02*
X413739Y-135779D01*
X414239Y-135179D01*
X414939Y-134979D01*
X415439Y-135179D01*
X416039Y-135779D01*
G01X422439Y-142979D02*
Y-134979D01*
G01Y-136379D02*
X422039Y-135579D01*
X421439Y-135179D01*
X420739Y-134979D01*
X420039Y-135379D01*
X419439Y-136179D01*
X419039Y-137379D01*
X418839Y-138979D01*
X419039Y-140579D01*
X419439Y-141779D01*
X420039Y-142579D01*
X420739Y-142979D01*
X421439Y-142779D01*
X422039Y-142179D01*
X422439Y-141379D01*
G01X428239Y-135979D02*
X427539Y-135179D01*
X426939Y-134979D01*
X426139Y-135379D01*
X425539Y-136179D01*
X425139Y-137579D01*
X425039Y-138979D01*
X425139Y-140379D01*
X425539Y-141579D01*
X426139Y-142579D01*
X426939Y-142979D01*
X427639Y-142579D01*
X428239Y-141779D01*
G01X431139Y-137579D02*
X434339D01*
X434039Y-136179D01*
X433539Y-135379D01*
X432839Y-134979D01*
X432139Y-135179D01*
X431539Y-135779D01*
X431139Y-137179D01*
X430939Y-138379D01*
Y-139579D01*
X431139Y-140779D01*
X431639Y-141979D01*
X432239Y-142779D01*
X432939Y-142979D01*
X433639Y-142579D01*
X434339Y-141379D01*
G01X437139Y-141579D02*
X437639Y-142379D01*
X438339Y-142979D01*
X438939D01*
X439539Y-142579D01*
X439939Y-141979D01*
X440139Y-141179D01*
X440039Y-139979D01*
X439639Y-139379D01*
X437839Y-138179D01*
X437439Y-136779D01*
X437639Y-135779D01*
X438039Y-135179D01*
X438639Y-134979D01*
X439239Y-135179D01*
X439839Y-135779D01*
G01X450639Y-134979D02*
Y-142979D01*
G01Y-131779D02*
X450439Y-131579D01*
Y-131179D01*
X450639Y-130979D01*
X450839Y-131179D01*
Y-131579D01*
X450639Y-131779D01*
G01X454939Y-142979D02*
Y-134979D01*
G01Y-136979D02*
X455339Y-135979D01*
X455939Y-135179D01*
X456739Y-134979D01*
X457439Y-135179D01*
X458039Y-135979D01*
X458339Y-137379D01*
Y-142979D01*
G01X468639D02*
Y-130979D01*
G01X476439Y-142979D02*
Y-134979D01*
G01Y-136379D02*
X476039Y-135579D01*
X475439Y-135179D01*
X474739Y-134979D01*
X474039Y-135379D01*
X473439Y-136179D01*
X473039Y-137379D01*
X472839Y-138979D01*
X473039Y-140579D01*
X473439Y-141779D01*
X474039Y-142579D01*
X474739Y-142979D01*
X475439Y-142779D01*
X476039Y-142179D01*
X476439Y-141379D01*
G01X478539Y-146579D02*
X479139Y-146979D01*
X479939Y-146579D01*
X480439Y-145779D01*
X480839Y-144779D01*
X481439Y-141579D01*
X482739Y-134979D01*
G01X479539D02*
X481439Y-141579D01*
G01X485139Y-137579D02*
X488339D01*
X488039Y-136179D01*
X487539Y-135379D01*
X486839Y-134979D01*
X486139Y-135179D01*
X485539Y-135779D01*
X485139Y-137179D01*
X484939Y-138379D01*
Y-139579D01*
X485139Y-140779D01*
X485639Y-141979D01*
X486239Y-142779D01*
X486939Y-142979D01*
X487639Y-142579D01*
X488339Y-141379D01*
G01X491239Y-142979D02*
Y-134979D01*
G01Y-136579D02*
X491739Y-135779D01*
X492239Y-135179D01*
X492939Y-134979D01*
X493439Y-135179D01*
X494039Y-135779D01*
G01X504639Y-130979D02*
Y-142979D01*
G01X502339Y-130979D02*
X506939D01*
G01X510639Y-142979D02*
X509839Y-142779D01*
X509139Y-141979D01*
X508539Y-140779D01*
X508139Y-139379D01*
X507939Y-137779D01*
Y-136179D01*
X508139Y-134579D01*
X508539Y-133179D01*
X509139Y-131979D01*
X509839Y-131179D01*
X510639Y-130979D01*
X511439Y-131179D01*
X512139Y-131979D01*
X512739Y-133179D01*
X513139Y-134579D01*
X513339Y-136179D01*
Y-137779D01*
X513139Y-139379D01*
X512739Y-140779D01*
X512139Y-141979D01*
X511439Y-142779D01*
X510639Y-142979D01*
G01X514639D02*
Y-130979D01*
X517039D01*
X517839Y-131579D01*
X518439Y-132979D01*
X518639Y-134579D01*
X518439Y-136179D01*
X517939Y-137379D01*
X517039Y-137979D01*
X514639D01*
G01X36516Y309567D02*
G02X22539I-6989J0D01*
G02X36516I6989J0D01*
G01Y1029528D02*
G02X22539I-6989J0D01*
G02X36516I6989J0D01*
G01X137795Y17717D02*
G02X122047I-7874J0D01*
G02X137795I7874J0D01*
G01X278642Y267717D02*
G02X264665I-6989J0D01*
G02X278642I6988J0D01*
G01Y673228D02*
G02X264665I-6989J0D01*
G02X278642I6988J0D01*
G01Y1078740D02*
G02X264665I-6989J0D01*
G02X278642I6988J0D01*
G01Y1484252D02*
G02X264665I-6989J0D01*
G02X278642I6988J0D01*
G01Y1889764D02*
G02X264665I-6989J0D01*
G02X278642I6988J0D01*
G01X1001083Y149606D02*
G02X987106I-6989J0D01*
G02X1001083I6988J0D01*
G01Y673228D02*
G02X987106I-6989J0D01*
G02X1001083I6988J0D01*
G01Y1068898D02*
G02X987106I-6989J0D01*
G02X1001083I6988J0D01*
G01X1001969Y1889764D02*
G02X986220I-7875J0D01*
G02X1001969I7874J0D01*
G01X1012008Y1416024D02*
G02X1026575I7284J0D01*
G02X1012008I-7283J0D01*
G01Y1694213D02*
G02X1026575I7284J0D01*
G02X1012008I-7283J0D01*
M02*
